P  JOB   t6m_pdb_d_0928_1400_274.brd
P  UNITS CUST 
P  DIM   N
C  
C  Nov 26 11:02:56 2013
C  
C  IPC-D-356 Netlist From Allegro
C  
317NNAME10000       J19   -8    D0390PA00X+001774Y+002495               S0      
317UART_TX_P1_L     J19   -6    D0390PA00X+002774Y+002495               S0      
317GND              VIA   -     D0100PA00X+002522Y+001875               S3      
317N/C              J19   -H2   D1320UA00X+001274Y+005995               S0      
317NNAME10001       J19   -7    D0390PA00X+002274Y+003495               S0      
317GND              VIA   -     D0100PA00X+000300Y+005203               S3      
317GND              VIA   -     D0100PA00X+000300Y+010003               S3      
317GND              VIA   -     D0100PA00X+000300Y+015003               S3      
317N/C              J21   -H1   D1320UA00X+001274Y+018198               S0      
317GND              VIA   -     D0100PA00X+000300Y+020003               S3      
317NNAME10002       J21   -2    D0390PA00X+002274Y+021698               S0      
317UART_RX_P2_L     J21   -3    D0390PA00X+002774Y+020698               S0      
317NNAME10003       J21   -1    D0390PA00X+001774Y+020698               S0      
317NNAME10004       J23   -8    D0390PA00X+001774Y+023381               S0      
317UART_TX_P5_L     J23   -6    D0390PA00X+002774Y+023381               S0      
317NNAME10005       J23   -7    D0390PA00X+002274Y+024381               S0      
317GND              VIA   -     D0100PA00X+000300Y+025003               S3      
317N/C              J23   -H2   D1320UA00X+001274Y+026881               S0      
317GND              VIA   -     D0100PA00X+000300Y+030003               S3      
317GND              VIA   -     D0100PA00X+000300Y+035003               S3      
317N/C              J27   -H1   D1320UA00X+001274Y+039083               S0      
317UART_RX_P6_L     J27   -3    D0390PA00X+002774Y+041583               S0      
317NNAME10006       J27   -1    D0390PA00X+001774Y+041583               S0      
317GND              VIA   -     D0100PA00X+000300Y+040003               S3      
317NNAME10007       J27   -2    D0390PA00X+002274Y+042583               S0      
317GND              VIA   -     D0100PA00X+000300Y+045003               S3      
317LAN1_P4_N        J29   -8    D0360PA00X+001900Y+050870               S0      
317GND              VIA   -     D0100PA00X+000300Y+050003               S3      
317N/C              J29   -H2   D1260UA00X+001400Y+054370               S0      
317GND              J29   -G2   D0630PA00X+000549Y+052854               S0      
317LAN1_P4_P        J29   -7    D0360PA00X+002400Y+051870               S0      
317N/C              J29   -11   D0360PA00X+002150Y+055988               S0      
317N42130542        J29   -12   D0360PA00X+001169Y+055988               S0      
317GND              VIA   -     D0100PA00X+000300Y+055003               S3      
327N42130542        R150  -2          A01X+001168Y+057281X0180Y0200R090 S2      
327GND              R150  -1          A01X+001168Y+057596X0180Y0200R090 S2      
317GND              VIA   -     D0100PA00X+001168Y+057877               S3      
317GND              J33   -2    D0400PA00X+001748Y+059990               S0      
317CM_PWR_CTL_IN    J33   -1    D0400PA00X+000961Y+059990               S0      
317GND              VIA   -     D0100PA00X+000300Y+060003               S3      
317GND              J30   -2    D0400PA00X+001748Y+062726               S0      
317NNAME10008       J30   -1    D0400PA00X+000961Y+062726               S0      
317GND              VIA   -     D0100PA00X+000300Y+065003               S3      
317MATE_A1          J26   -B81  D0280PA00X+001555Y+070736               S0      
317P12V             J26   -A81  D0280PA00X+002539Y+070736               S0      
317P12V             J26   -B82  D0280PA00X+000767Y+070343               S0      
317N/C              J26   -H2   D0950UA00X+002047Y+069634               S0      
317GND              VIA   -     D0100PA00X+000300Y+070003               S3      
317P12V             J26   -B79  D0280PA00X+001555Y+071524               S0      
317GND              J26   -B77  D0280PA00X+001555Y+072311               S0      
317LAN1_P4_P        J26   -B75  D0280PA00X+001555Y+073099               S0      
317P12V             J26   -A79  D0280PA00X+002539Y+071524               S0      
317GND              J26   -A77  D0280PA00X+002539Y+072311               S0      
317LAN1_P2_P        J26   -A75  D0280PA00X+002539Y+073099               S0      
317P12V             J26   -B80  D0280PA00X+000767Y+071130               S0      
317CM_PWR_CTL_IN    J26   -B78  D0280PA00X+000767Y+071918               S0      
317LAN1_P4_N        J26   -B76  D0280PA00X+000767Y+072705               S0      
317LAN1_P3_N        J26   -B73  D0280PA00X+001555Y+073886               S0      
317GND              J26   -B71  D0280PA00X+001555Y+074673               S0      
317GND29            J26   -B69  D0280PA00X+001555Y+075461               S0      
317LAN1_P1_N        J26   -A73  D0280PA00X+002539Y+073886               S0      
317GND              J26   -A71  D0280PA00X+002539Y+074673               S0      
317N/C              J26   -A69  D0280PA00X+002539Y+075461               S0      
317GND              J26   -B74  D0280PA00X+000767Y+073492               S0      
317LAN1_P3_P        J26   -B72  D0280PA00X+000767Y+074280               S0      
317N/C              J26   -B70  D0280PA00X+000767Y+075067               S0      
317GND28            J26   -B68  D0280PA00X+000767Y+075855               S0      
317GND              VIA   -     D0100PA00X+000300Y+075003               S3      
317N/C              J26   -B67  D0280PA00X+001555Y+076248               S0      
317NNAME10000       J26   -B65  D0280PA00X+001555Y+077036               S0      
317UART_TX_P1_L     J26   -B63  D0280PA00X+001555Y+077823               S0      
317N/C              J26   -A67  D0280PA00X+002539Y+076248               S0      
317NNAME10009       J26   -A65  D0280PA00X+002539Y+077036               S0      
317UART_TX_P2_L     J26   -A63  D0280PA00X+002539Y+077823               S0      
317GND              J26   -B66  D0280PA00X+000767Y+076642               S0      
317NNAME10001       J26   -B64  D0280PA00X+000767Y+077429               S0      
317UART_RX_P1_L     J26   -B62  D0280PA00X+000767Y+078217               S0      
317NNAME10010       J26   -B61  D0280PA00X+001555Y+078611               S0      
317GND              J26   -B59  D0280PA00X+001555Y+079398               S0      
317NNAME10004       J26   -B57  D0280PA00X+001555Y+080185               S0      
317NNAME10002       J26   -A61  D0280PA00X+002539Y+078611               S0      
317GND              J26   -A59  D0280PA00X+002539Y+079398               S0      
317NNAME10011       J26   -A57  D0280PA00X+002539Y+080185               S0      
317NNAME10012       J26   -B60  D0280PA00X+000767Y+079004               S0      
317UART_RI_P5_L_N   J26   -B58  D0280PA00X+000767Y+079792               S0      
317NNAME10005       J26   -B56  D0280PA00X+000767Y+080579               S0      
317GND              VIA   -     D0100PA00X+000300Y+080003               S3      
317UART_TX_P5_L     J26   -B55  D0280PA00X+001555Y+080973               S0      
317NNAME10013       J26   -B53  D0280PA00X+001555Y+081760               S0      
317GND              J26   -B51  D0280PA00X+001555Y+082548               S0      
317UART_TX_P6_L     J26   -A55  D0280PA00X+002539Y+080973               S0      
317NNAME10007       J26   -A53  D0280PA00X+002539Y+081760               S0      
317GND              J26   -A51  D0280PA00X+002539Y+082548               S0      
317UART_RX_P5_L     J26   -B54  D0280PA00X+000767Y+081366               S0      
317NNAME10014       J26   -B52  D0280PA00X+000767Y+082154               S0      
317PSU6_AC_OK       J26   -B50  D0280PA00X+000767Y+082941               S0      
317PSU5_AC_OK       J26   -B49  D0280PA00X+001555Y+083335               S0      
317PSU3_AC_OK       J26   -B47  D0280PA00X+001555Y+084122               S0      
317PSU1_AC_OK       J26   -B45  D0280PA00X+001555Y+084910               S0      
317PSU5_DC_OK       J26   -A49  D0280PA00X+002539Y+083335               S0      
317PSU3_DC_OK       J26   -A47  D0280PA00X+002539Y+084122               S0      
317PSU1_DC_OK       J26   -A45  D0280PA00X+002539Y+084910               S0      
317PSU4_AC_OK       J26   -B48  D0280PA00X+000767Y+083729               S0      
317PSU2_AC_OK       J26   -B46  D0280PA00X+000767Y+084516               S0      
317GND              J26   -B44  D0280PA00X+000767Y+085303               S0      
317GND              VIA   -     D0100PA00X+000300Y+085003               S3      
317I2C_PSU1_SDA     J26   -B43  D0280PA00X+001555Y+085697               S0      
317GND              J26   -B41  D0280PA00X+001555Y+086485               S0      
317T2_BLAD4_RXD     J26   -B39  D0280PA00X+001555Y+087272               S0      
317T1_BLAD1_TXD     J26   -A43  D0280PA00X+002539Y+085697               S0      
317T1_BLAD4_TXD     J26   -A41  D0280PA00X+002539Y+086485               S0      
317GND              J26   -A39  D0280PA00X+002539Y+087272               S0      
317I2C_PSU1_SCL     J26   -B42  D0280PA00X+000767Y+086091               S0      
317T2_BLAD4_TXD     J26   -B40  D0280PA00X+000767Y+086878               S0      
317T2_BLAD3_TXD     J26   -B38  D0280PA00X+000767Y+087666               S0      
317T2_BLAD3_RXD     J26   -B37  D0280PA00X+001555Y+088059               S0      
317T2_BLAD2_TXD     J26   -B35  D0280PA00X+001555Y+088847               S0      
317T2_BLAD1_TXD     J26   -B33  D0280PA00X+001555Y+089634               S0      
317T1_BLAD3_RXD     J26   -A37  D0280PA00X+002539Y+088059               S0      
317T1_BLAD2_RXD     J26   -A35  D0280PA00X+002539Y+088847               S0      
317T1_BLAD4_EN      J26   -A33  D0280PA00X+002539Y+089634               S0      
317GND              J26   -B36  D0280PA00X+000767Y+088453               S0      
317T2_BLAD2_RXD     J26   -B34  D0280PA00X+000767Y+089240               S0      
317T2_BLAD1_RXD     J26   -B32  D0280PA00X+000767Y+090028               S0      
317GND              VIA   -     D0100PA00X+000300Y+090003               S3      
317GND              J26   -B31  D0280PA00X+001555Y+090422               S0      
317T2_BLAD3_EN      J26   -B29  D0280PA00X+001555Y+091209               S0      
317T2_BLAD1_EN      J26   -B27  D0280PA00X+001555Y+091996               S0      
317T1_BLAD2_EN      J26   -A31  D0280PA00X+002539Y+090422               S0      
317GND              J26   -A29  D0280PA00X+002539Y+091209               S0      
317T3_BLAD4_RXD     J26   -A27  D0280PA00X+002539Y+091996               S0      
317T2_BLAD4_EN      J26   -B30  D0280PA00X+000767Y+090815               S0      
317T2_BLAD2_EN      J26   -B28  D0280PA00X+000767Y+091603               S0      
317GND              J26   -B26  D0280PA00X+000767Y+092390               S0      
317T4_BLAD4_TXD     J26   -B25  D0280PA00X+001555Y+092784               S0      
317T4_BLAD3_TXD     J26   -B23  D0280PA00X+001555Y+093571               S0      
317GND              J26   -B21  D0280PA00X+001555Y+094359               S0      
317T4_BLAD2_RXD     J26   -B19  D0280PA00X+001555Y+095146               S0      
317T3_BLAD3_RXD     J26   -A25  D0280PA00X+002539Y+092784               S0      
317T3_BLAD2_TXD     J26   -A23  D0280PA00X+002539Y+093571               S0      
317T3_BLAD1_TXD     J26   -A21  D0280PA00X+002539Y+094359               S0      
317GND              J26   -A19  D0280PA00X+002539Y+095146               S0      
317T4_BLAD4_RXD     J26   -B24  D0280PA00X+000767Y+093177               S0      
317T4_BLAD3_RXD     J26   -B22  D0280PA00X+000767Y+093965               S0      
317T4_BLAD2_TXD     J26   -B20  D0280PA00X+000767Y+094752               S0      
317GND              VIA   -     D0100PA00X+000300Y+095003               S3      
317T4_BLAD1_RXD     J26   -B17  D0280PA00X+001555Y+095933               S0      
317T4_BLAD4_EN      J26   -B15  D0280PA00X+001555Y+096721               S0      
317T4_BLAD2_EN      J26   -B13  D0280PA00X+001555Y+097508               S0      
317T3_BLAD3_EN      J26   -A17  D0280PA00X+002539Y+095933               S0      
317T3_BLAD1_EN      J26   -A15  D0280PA00X+002539Y+096721               S0      
317T5_BLAD4_TXD     J26   -A13  D0280PA00X+002539Y+097508               S0      
317T4_BLAD1_TXD     J26   -B18  D0280PA00X+000767Y+095540               S0      
317GND              J26   -B16  D0280PA00X+000767Y+096327               S0      
317T4_BLAD3_EN      J26   -B14  D0280PA00X+000767Y+097114               S0      
317T4_BLAD1_EN      J26   -B12  D0280PA00X+000767Y+097902               S0      
317I2C_PSU2_SCL     J26   -B10  D0280PA00X+000767Y+099477               S0      
317I2C_PSU2_SDA     J26   -B11  D0280PA00X+001555Y+099083               S0      
317GND              J26   -B9   D0280PA00X+001555Y+099870               S0      
317T5_BLAD3_TXD     J26   -A11  D0280PA00X+002539Y+099083               S0      
317T5_BLAD2_TXD     J26   -A9   D0280PA00X+002539Y+099870               S0      
317N/C              J26   -H1   D0950UA00X+002047Y+098433               S0      
317T6_BLAD4_TXD     J26   -B8   D0280PA00X+000767Y+100264               S0      
317T6_BLAD3_TXD     J26   -B6   D0280PA00X+000767Y+101051               S0      
317GND              J26   -B4   D0280PA00X+000767Y+101839               S0      
317T6_BLAD4_RXD     J26   -B7   D0280PA00X+001555Y+100658               S0      
317T6_BLAD3_RXD     J26   -B5   D0280PA00X+001555Y+101445               S0      
317T6_BLAD2_TXD     J26   -B3   D0280PA00X+001555Y+102233               S0      
317GND              J26   -A7   D0280PA00X+002539Y+100658               S0      
317T5_BLAD1_RXD     J26   -A5   D0280PA00X+002539Y+101445               S0      
317T5_BLAD4_EN      J26   -A3   D0280PA00X+002539Y+102233               S0      
317GND              VIA   -     D0100PA00X+000300Y+100003               S3      
317T6_BLAD2_RXD     J26   -B2   D0280PA00X+000767Y+102626               S0      
317GND              J26   -B1   D0280PA00X+001555Y+103020               S0      
317GND              J26   -A1   D0280PA00X+002539Y+103020               S0      
317T6_BLAD1_RXD     J25   -B81  D0280PA00X+001555Y+106563               S0      
317T5_BLAD1_EN      J25   -A81  D0280PA00X+002539Y+106563               S0      
317T6_BLAD1_TXD     J25   -B82  D0280PA00X+000768Y+106169               S0      
317GND              J25   -B80  D0280PA00X+000768Y+106957               S0      
317N/C              J25   -H2   D0950UA00X+002047Y+105461               S0      
317GND              VIA   -     D0100PA00X+000300Y+105003               S3      
317T6_BLAD4_EN      J25   -B79  D0280PA00X+001555Y+107350               S0      
317T6_BLAD2_EN      J25   -B77  D0280PA00X+001555Y+108138               S0      
317GND              J25   -B75  D0280PA00X+001555Y+108925               S0      
317GND              J25   -A79  D0280PA00X+002539Y+107350               S0      
317T7_BLAD4_RXD     J25   -A77  D0280PA00X+002539Y+108138               S0      
317T7_BLAD3_RXD     J25   -A75  D0280PA00X+002539Y+108925               S0      
317T6_BLAD3_EN      J25   -B78  D0280PA00X+000768Y+107744               S0      
317T6_BLAD1_EN      J25   -B76  D0280PA00X+000768Y+108531               S0      
317T8_BLAD4_TXD     J25   -B74  D0280PA00X+000768Y+109319               S0      
317T8_BLAD4_RXD     J25   -B73  D0280PA00X+001555Y+109713               S0      
317T8_BLAD3_RXD     J25   -B71  D0280PA00X+001555Y+110500               S0      
317T8_BLAD2_TXD     J25   -B69  D0280PA00X+001555Y+111287               S0      
317T8_BLAD1_TXD     J25   -B67  D0280PA00X+001555Y+112075               S0      
317T7_BLAD2_TXD     J25   -A73  D0280PA00X+002539Y+109713               S0      
317T7_BLAD1_TXD     J25   -A71  D0280PA00X+002539Y+110500               S0      
317GND              J25   -A69  D0280PA00X+002539Y+111287               S0      
317T7_BLAD3_EN      J25   -A67  D0280PA00X+002539Y+112075               S0      
317T8_BLAD3_TXD     J25   -B72  D0280PA00X+000768Y+110106               S0      
317GND              J25   -B70  D0280PA00X+000768Y+110894               S0      
317T8_BLAD2_RXD     J25   -B68  D0280PA00X+000768Y+111681               S0      
317GND              VIA   -     D0100PA00X+000300Y+110003               S3      
317GND              J25   -B65  D0280PA00X+001555Y+112862               S0      
317T8_BLAD3_EN      J25   -B63  D0280PA00X+001555Y+113650               S0      
317T8_BLAD1_EN      J25   -B61  D0280PA00X+001555Y+114437               S0      
317T7_BLAD1_EN      J25   -A65  D0280PA00X+002539Y+112862               S0      
317T9_BLAD4_TXD     J25   -A63  D0280PA00X+002539Y+113650               S0      
317T9_BLAD3_TXD     J25   -A61  D0280PA00X+002539Y+114437               S0      
317T8_BLAD1_RXD     J25   -B66  D0280PA00X+000768Y+112468               S0      
317T8_BLAD4_EN      J25   -B64  D0280PA00X+000768Y+113256               S0      
317T8_BLAD2_EN      J25   -B62  D0280PA00X+000768Y+114043               S0      
317T10_BLAD4_TXD    J25   -B59  D0280PA00X+001555Y+115224               S0      
317T10_BLAD3_TXD    J25   -B57  D0280PA00X+001555Y+116012               S0      
317GND              J25   -B55  D0280PA00X+001555Y+116799               S0      
317GND              J25   -A59  D0280PA00X+002539Y+115224               S0      
317T9_BLAD2_RXD     J25   -A57  D0280PA00X+002539Y+116012               S0      
317T9_BLAD1_RXD     J25   -A55  D0280PA00X+002539Y+116799               S0      
317GND              J25   -B60  D0280PA00X+000768Y+114831               S0      
317T10_BLAD4_RXD    J25   -B58  D0280PA00X+000768Y+115618               S0      
317T10_BLAD3_RXD    J25   -B56  D0280PA00X+000768Y+116406               S0      
317GND              VIA   -     D0100PA00X+000300Y+115003               S3      
317T10_BLAD2_RXD    J25   -B53  D0280PA00X+001555Y+117587               S0      
317T10_BLAD1_RXD    J25   -B51  D0280PA00X+001555Y+118374               S0      
317T10_BLAD4_EN     J25   -B49  D0280PA00X+001555Y+119161               S0      
317T9_BLAD4_EN      J25   -A53  D0280PA00X+002539Y+117587               S0      
317T9_BLAD2_EN      J25   -A51  D0280PA00X+002539Y+118374               S0      
317GND              J25   -A49  D0280PA00X+002539Y+119161               S0      
317T10_BLAD2_TXD    J25   -B54  D0280PA00X+000768Y+117193               S0      
317T10_BLAD1_TXD    J25   -B52  D0280PA00X+000768Y+117980               S0      
317GND              J25   -B50  D0280PA00X+000768Y+118768               S0      
317T10_BLAD2_EN     J25   -B47  D0280PA00X+001555Y+119949               S0      
317GND              J25   -B45  D0280PA00X+001555Y+120736               S0      
317T12_BLAD4_RXD    J25   -B43  D0280PA00X+001555Y+121524               S0      
317T11_BLAD4_RXD    J25   -A47  D0280PA00X+002539Y+119949               S0      
317T11_BLAD3_RXD    J25   -A45  D0280PA00X+002539Y+120736               S0      
317T11_BLAD2_TXD    J25   -A43  D0280PA00X+002539Y+121524               S0      
317T10_BLAD3_EN     J25   -B48  D0280PA00X+000768Y+119555               S0      
317T10_BLAD1_EN     J25   -B46  D0280PA00X+000768Y+120343               S0      
317T12_BLAD4_TXD    J25   -B44  D0280PA00X+000768Y+121130               S0      
317GND              VIA   -     D0100PA00X+000300Y+120003               S3      
317T12_BLAD3_RXD    J25   -B41  D0280PA00X+001555Y+122311               S0      
317T12_BLAD2_TXD    J25   -B39  D0280PA00X+001555Y+123098               S0      
317T12_BLAD1_TXD    J25   -B37  D0280PA00X+001555Y+123886               S0      
317T11_BLAD1_TXD    J25   -A41  D0280PA00X+002539Y+122311               S0      
317GND              J25   -A39  D0280PA00X+002539Y+123098               S0      
317T11_BLAD3_EN     J25   -A37  D0280PA00X+002539Y+123886               S0      
317T12_BLAD3_TXD    J25   -B42  D0280PA00X+000768Y+121917               S0      
317GND              J25   -B40  D0280PA00X+000768Y+122705               S0      
317T12_BLAD2_RXD    J25   -B38  D0280PA00X+000768Y+123492               S0      
317GND              J25   -B35  D0280PA00X+001555Y+124673               S0      
317T12_BLAD3_EN     J25   -B33  D0280PA00X+001555Y+125461               S0      
317T12_BLAD1_EN     J25   -B31  D0280PA00X+001555Y+126248               S0      
317T11_BLAD1_EN     J25   -A35  D0280PA00X+002539Y+124673               S0      
317I2C_PSU3_SDA     J25   -A33  D0280PA00X+002539Y+125461               S0      
317GND              J25   -A31  D0280PA00X+002539Y+126248               S0      
317T12_BLAD1_RXD    J25   -B36  D0280PA00X+000768Y+124280               S0      
317T12_BLAD4_EN     J25   -B34  D0280PA00X+000768Y+125067               S0      
317T12_BLAD2_EN     J25   -B32  D0280PA00X+000768Y+125854               S0      
317GND              VIA   -     D0100PA00X+000300Y+125003               S3      
317FAN3_TACH        J25   -B29  D0280PA00X+001555Y+127035               S0      
317FAN1_TACH        J25   -B27  D0280PA00X+001555Y+127823               S0      
317NNAME10015       J25   -B25  D0280PA00X+001555Y+128610               S0      
317GND              J25   -A29  D0280PA00X+002539Y+127035               S0      
317FAN5_TACH        J25   -A27  D0280PA00X+002539Y+127823               S0      
317GND              J25   -A25  D0280PA00X+002539Y+128610               S0      
317GND              J25   -B30  D0280PA00X+000768Y+126642               S0      
317FAN2_TACH        J25   -B28  D0280PA00X+000768Y+127429               S0      
317GND              J25   -B26  D0280PA00X+000768Y+128217               S0      
317NNAME10016       J25   -B23  D0280PA00X+001555Y+129398               S0      
317UART_RX_RP5_L    J25   -B21  D0280PA00X+001555Y+130185               S0      
317NNAME10017       J25   -B19  D0280PA00X+001555Y+130972               S0      
317NNAME10018       J25   -A23  D0280PA00X+002539Y+129398               S0      
317UART_TX_RP6_L    J25   -A21  D0280PA00X+002539Y+130185               S0      
317UART_DSR_RP6_L   J25   -A19  D0280PA00X+002539Y+130972               S0      
317NNAME10019       J25   -B24  D0280PA00X+000768Y+129004               S0      
317UART_TX_RP5_L    J25   -B22  D0280PA00X+000768Y+129791               S0      
317UART_DSR_RP5_L   J25   -B20  D0280PA00X+000768Y+130579               S0      
317GND              J25   -B18  D0280PA00X+000768Y+131366               S0      
317GND              VIA   -     D0100PA00X+000300Y+130003               S3      
317N/C              J25   -B17  D0280PA00X+001555Y+131760               S0      
317N/C              J25   -B15  D0280PA00X+001555Y+132547               S0      
317GND3             J25   -B13  D0280PA00X+001555Y+133335               S0      
317GND              J25   -A17  D0280PA00X+002539Y+131760               S0      
317GND37            J25   -A15  D0280PA00X+002539Y+132547               S0      
317N/C              J25   -A13  D0280PA00X+002539Y+133335               S0      
317GND4             J25   -B16  D0280PA00X+000768Y+132154               S0      
317N/C              J25   -B14  D0280PA00X+000768Y+132941               S0      
317P3V3             J25   -B12  D0280PA00X+000768Y+133728               S0      
317I2C_PDB_SCL      J25   -B10  D0280PA00X+000768Y+135303               S0      
317GND              J25   -B8   D0280PA00X+000768Y+136091               S0      
317I2C_PDB_SDA      J25   -B11  D0280PA00X+001555Y+134909               S0      
317GND              J25   -B9   D0280PA00X+001555Y+135697               S0      
317NNAME10020       J25   -A11  D0280PA00X+002539Y+134909               S0      
317NNAME10008       J25   -A9   D0280PA00X+002539Y+135697               S0      
317N/C              J25   -H1   D0950UA00X+002047Y+134260               S0      
317GND              VIA   -     D0100PA00X+000300Y+135003               S3      
317LAN2_P2_N        J25   -B6   D0280PA00X+000768Y+136878               S0      
317GND              J25   -B4   D0280PA00X+000768Y+137665               S0      
317LAN2_P1_P        J25   -B2   D0280PA00X+000768Y+138453               S0      
317GND              J25   -B7   D0280PA00X+001555Y+136484               S0      
317LAN2_P2_P        J25   -B5   D0280PA00X+001555Y+137272               S0      
317LAN2_P1_N        J25   -B3   D0280PA00X+001555Y+138059               S0      
317LAN2_P4_N        J25   -A7   D0280PA00X+002539Y+136484               S0      
317GND              J25   -A5   D0280PA00X+002539Y+137272               S0      
317LAN2_P3_P        J25   -A3   D0280PA00X+002539Y+138059               S0      
317GND              J25   -B1   D0280PA00X+001555Y+138846               S0      
317MATE_A1          J25   -A1   D0280PA00X+002539Y+138846               S0      
317GND              VIA   -     D0100PA00X+000300Y+140003               S3      
317GND              VIA   -     D0100PA00X+000300Y+145003               S3      
317GND              J31   -2    D0400PA00X+001748Y+147195               S0      
317NNAME10021       J31   -1    D0400PA00X+000961Y+147195               S0      
317GND              J32   -2    D0400PA00X+001748Y+149931               S0      
317NNAME10020       J32   -1    D0400PA00X+000961Y+149931               S0      
317GND              VIA   -     D0100PA00X+000300Y+150003               S3      
317GND              VIA   -     D0100PA00X+000300Y+155003               S3      
317GND              VIA   -     D0100PA00X+001648Y+155216               S3      
317GND              VIA   -     D0100PA00X+001109Y+155259               S3      
327GND              R151  -2          A01X+001648Y+155516X0180Y0200R090 S2      
327N42132545        R151  -1          A01X+001648Y+155831X0180Y0200R090 S2      
327GND              R152  -2          A01X+001109Y+155529X0180Y0200R090 S2      
327N42132933        R152  -1          A01X+001109Y+155844X0180Y0200R090 S2      
317N42132545        J28   -10   D0360PA00X+002150Y+157181               S0      
317N42132933        J28   -9    D0360PA00X+001169Y+157181               S0      
317N/C              J28   -H1   D1260UA00X+001400Y+158799               S0      
317GND              J28   -G1   D0630PA00X+000549Y+160315               S0      
317GND              VIA   -     D0100PA00X+000301Y+159460               S3      
317LAN2_P1_N        J28   -2    D0360PA00X+002400Y+162299               S0      
317LAN2_P1_P        J28   -1    D0360PA00X+001900Y+161299               S0      
317GND              VIA   -     D0100PA00X+000301Y+161017               S3      
317GND              VIA   -     D0100PA00X+000300Y+165003               S3      
317FAN_PWM          J20   -20   D0570PA00X+002340Y+166887               S0      
317GND              J20   -19   D0570PA00X+002340Y+168541               S0      
317GND              J20   -18   D0570PA00X+002340Y+170195               S0      
317FAN_PWM          J20   -17   D0570PA00X+002340Y+171848               S0      
317GND              VIA   -     D0100PA00X+000300Y+170003               S3      
317GND              J20   -16   D0570PA00X+002340Y+173502               S0      
317GND              J20   -15   D0570PA00X+002340Y+175155               S0      
317FAN6_TACH        J20   -14   D0570PA00X+002340Y+176809               S0      
317GND              VIA   -     D0100PA00X+000300Y+175003               S3      
317GND              J20   -13   D0570PA00X+002340Y+178462               S0      
317FAN5_TACH        J20   -11   D0570PA00X+002340Y+181769               S0      
317GND              J20   -12   D0570PA00X+002340Y+180116               S0      
317GND              VIA   -     D0100PA00X+000300Y+180003               S3      
317GND              VIA   -     D0100PA00X+000300Y+185003               S3      
317N/C              J22   -H1   D1320UA00X+001274Y+192229               S0      
317GND              VIA   -     D0100PA00X+000300Y+190003               S3      
317UART_DSR_RP5_L   J22   -2    D0390PA00X+002274Y+195729               S0      
317UART_RX_RP5_L    J22   -3    D0390PA00X+002774Y+194729               S0      
317NNAME10017       J22   -1    D0390PA00X+001774Y+194729               S0      
317GND              VIA   -     D0100PA00X+000300Y+195003               S3      
317GND              VIA   -     D0100PA00X+000300Y+200003               S3      
317N/C              J24   -H1   D1320UA00X+001274Y+202666               S0      
317UART_DSR_RP6_L   J24   -2    D0390PA00X+002274Y+206166               S0      
317UART_RX_RP6_L    J24   -3    D0390PA00X+002774Y+205166               S0      
317NNAME10022       J24   -1    D0390PA00X+001774Y+205166               S0      
317GND              VIA   -     D0100PA00X+000300Y+205003               S3      
317GND              J19   -4    D0390PA00X+003774Y+002495               S0      
317NNAME10010       J19   -2    D0390PA00X+004774Y+002495               S0      
317GND              J19   -5    D0390PA00X+003274Y+003495               S0      
317UART_RX_P1_L     J19   -3    D0390PA00X+004274Y+003495               S0      
317UART_TX_P2_L     J21   -6    D0390PA00X+004274Y+021698               S0      
317GND              J21   -4    D0390PA00X+003274Y+021698               S0      
317NNAME10023       J21   -7    D0390PA00X+004774Y+020698               S0      
317GND              J21   -5    D0390PA00X+003774Y+020698               S0      
317UART_RI_P5_L_N   J23   -4    D0390PA00X+003774Y+023381               S0      
317NNAME10013       J23   -2    D0390PA00X+004774Y+023381               S0      
317GND              J23   -5    D0390PA00X+003274Y+024381               S0      
317UART_RX_P5_L     J23   -3    D0390PA00X+004274Y+024381               S0      
317NNAME10024       J27   -7    D0390PA00X+004774Y+041583               S0      
317GND              J27   -5    D0390PA00X+003774Y+041583               S0      
317UART_TX_P6_L     J27   -6    D0390PA00X+004274Y+042583               S0      
317UART_RI_P6_L_N   J27   -4    D0390PA00X+003274Y+042583               S0      
317LAN1_P2_N        J29   -6    D0360PA00X+002900Y+050870               S0      
317LAN1_P3_P        J29   -4    D0360PA00X+003900Y+050870               S0      
317LAN1_P1_N        J29   -2    D0360PA00X+004900Y+050870               S0      
317LAN1_P3_N        J29   -5    D0360PA00X+003400Y+051870               S0      
317LAN1_P2_P        J29   -3    D0360PA00X+004400Y+051870               S0      
317N42126673        J29   -10   D0360PA00X+005150Y+055988               S0      
317P12V             J26   -A82  D0280PA00X+003326Y+070343               S0      
317P12V             J26   -A80  D0280PA00X+003326Y+071130               S0      
317P12V             J26   -A78  D0280PA00X+003326Y+071918               S0      
317LAN1_P2_N        J26   -A76  D0280PA00X+003326Y+072705               S0      
317GND              J26   -A74  D0280PA00X+003326Y+073492               S0      
317LAN1_P1_P        J26   -A72  D0280PA00X+003326Y+074280               S0      
317GND61            J26   -A70  D0280PA00X+003326Y+075067               S0      
317N/C              J26   -A68  D0280PA00X+003326Y+075855               S0      
317GND              J26   -A66  D0280PA00X+003326Y+076642               S0      
317NNAME10023       J26   -A64  D0280PA00X+003326Y+077429               S0      
317UART_RX_P2_L     J26   -A62  D0280PA00X+003326Y+078217               S0      
317NNAME10003       J26   -A60  D0280PA00X+003326Y+079004               S0      
317UART_RI_P6_L_N   J26   -A58  D0280PA00X+003326Y+079792               S0      
317NNAME10024       J26   -A56  D0280PA00X+003326Y+080579               S0      
317UART_RX_P6_L     J26   -A54  D0280PA00X+003326Y+081366               S0      
317NNAME10006       J26   -A52  D0280PA00X+003326Y+082154               S0      
317PSU6_DC_OK       J26   -A50  D0280PA00X+003326Y+082941               S0      
317PSU4_DC_OK       J26   -A48  D0280PA00X+003326Y+083729               S0      
317PSU2_DC_OK       J26   -A46  D0280PA00X+003326Y+084516               S0      
317GND              J26   -A44  D0280PA00X+003326Y+085303               S0      
317T1_BLAD1_RXD     J26   -A42  D0280PA00X+003326Y+086091               S0      
317T1_BLAD4_RXD     J26   -A40  D0280PA00X+003326Y+086878               S0      
317T1_BLAD3_TXD     J26   -A38  D0280PA00X+003326Y+087666               S0      
317T1_BLAD1_TXD     VIA   -     D0100PA00X+004843Y+086618               S3      
317T1_BLAD1_RXD     VIA   -     D0100PA00X+004847Y+086928               S3      
317T1_BLAD2_TXD     J26   -A36  D0280PA00X+003326Y+088453               S0      
317GND              J26   -A34  D0280PA00X+003326Y+089240               S0      
317T1_BLAD3_EN      J26   -A32  D0280PA00X+003326Y+090028               S0      
317T1_BLAD1_EN      J26   -A30  D0280PA00X+003326Y+090815               S0      
317T3_BLAD4_TXD     J26   -A28  D0280PA00X+003326Y+091603               S0      
317T3_BLAD3_TXD     J26   -A26  D0280PA00X+003326Y+092390               S0      
317GND              J26   -A24  D0280PA00X+003326Y+093177               S0      
317T3_BLAD2_RXD     J26   -A22  D0280PA00X+003326Y+093965               S0      
317T3_BLAD1_RXD     J26   -A20  D0280PA00X+003326Y+094752               S0      
317T3_BLAD4_EN      J26   -A18  D0280PA00X+003326Y+095540               S0      
317T3_BLAD2_EN      J26   -A16  D0280PA00X+003326Y+096327               S0      
317GND              J26   -A14  D0280PA00X+003326Y+097114               S0      
317T5_BLAD4_RXD     J26   -A12  D0280PA00X+003326Y+097902               S0      
317T5_BLAD3_RXD     J26   -A10  D0280PA00X+003326Y+099477               S0      
317T5_BLAD2_RXD     J26   -A8   D0280PA00X+003326Y+100264               S0      
317T5_BLAD1_TXD     J26   -A6   D0280PA00X+003326Y+101051               S0      
317GND              J26   -A4   D0280PA00X+003326Y+101839               S0      
317T5_BLAD3_EN      J26   -A2   D0280PA00X+003326Y+102626               S0      
317T5_BLAD2_EN      J25   -A82  D0280PA00X+003327Y+106169               S0      
317PSU_ALERT_N      J25   -A80  D0280PA00X+003327Y+106957               S0      
317T7_BLAD4_TXD     J25   -A78  D0280PA00X+003327Y+107744               S0      
317T7_BLAD3_TXD     J25   -A76  D0280PA00X+003327Y+108531               S0      
317GND              J25   -A74  D0280PA00X+003327Y+109319               S0      
317T7_BLAD2_RXD     J25   -A72  D0280PA00X+003327Y+110106               S0      
317T7_BLAD1_RXD     J25   -A70  D0280PA00X+003327Y+110894               S0      
317T7_BLAD4_EN      J25   -A68  D0280PA00X+003327Y+111681               S0      
317T7_BLAD2_EN      J25   -A66  D0280PA00X+003327Y+112468               S0      
317GND              J25   -A64  D0280PA00X+003327Y+113256               S0      
317T9_BLAD4_RXD     J25   -A62  D0280PA00X+003327Y+114043               S0      
317T9_BLAD3_RXD     J25   -A60  D0280PA00X+003327Y+114831               S0      
317T9_BLAD2_TXD     J25   -A58  D0280PA00X+003327Y+115618               S0      
317T9_BLAD1_TXD     J25   -A56  D0280PA00X+003327Y+116406               S0      
317GND              J25   -A54  D0280PA00X+003327Y+117193               S0      
317T9_BLAD3_EN      J25   -A52  D0280PA00X+003327Y+117980               S0      
317T9_BLAD1_EN      J25   -A50  D0280PA00X+003327Y+118768               S0      
317T11_BLAD4_TXD    J25   -A48  D0280PA00X+003327Y+119555               S0      
317T11_BLAD3_TXD    J25   -A46  D0280PA00X+003327Y+120343               S0      
317GND              J25   -A44  D0280PA00X+003327Y+121130               S0      
317T11_BLAD2_RXD    J25   -A42  D0280PA00X+003327Y+121917               S0      
317T11_BLAD1_RXD    J25   -A40  D0280PA00X+003327Y+122705               S0      
317T11_BLAD4_EN     J25   -A38  D0280PA00X+003327Y+123492               S0      
317T11_BLAD2_TXD    VIA   -     D0100PA00X+004944Y+123896               S1      
317T11_BLAD2_EN     J25   -A36  D0280PA00X+003327Y+124280               S0      
317GND              J25   -A34  D0280PA00X+003327Y+125067               S0      
317I2C_PSU3_SCL     J25   -A32  D0280PA00X+003327Y+125854               S0      
317FAN_PWM          J25   -A30  D0280PA00X+003327Y+126642               S0      
317FAN6_TACH        J25   -A28  D0280PA00X+003327Y+127429               S0      
317FAN4_TACH        J25   -A26  D0280PA00X+003327Y+128217               S0      
317NNAME10025       J25   -A24  D0280PA00X+003327Y+129004               S0      
317NNAME10026       J25   -A22  D0280PA00X+003327Y+129791               S0      
317UART_RX_RP6_L    J25   -A20  D0280PA00X+003327Y+130579               S0      
317NNAME10022       J25   -A18  D0280PA00X+003327Y+131366               S0      
317N/C              J25   -A16  D0280PA00X+003327Y+132154               S0      
317N/C              J25   -A14  D0280PA00X+003327Y+132941               S0      
317GND36            J25   -A12  D0280PA00X+003327Y+133728               S0      
317P3V3             VIA   -     D0100PA00X+004698Y+133584               S1      
317GND3             VIA   -     D0100PA00X+004698Y+132584               S1      
317GND4             VIA   -     D0100PA00X+004698Y+131584               S1      
317GND37            VIA   -     D0100PA00X+004698Y+132084               S1      
317GND36            VIA   -     D0100PA00X+004698Y+133084               S1      
317NNAME10021       J25   -A10  D0280PA00X+003327Y+135303               S0      
317GND              J25   -A8   D0280PA00X+003327Y+136091               S0      
317I2C_PDB_SCL      VIA   -     D0100PA00X+004698Y+134584               S1      
317I2C_PDB_SDA      VIA   -     D0100PA00X+004698Y+134084               S1      
317LAN2_P4_P        J25   -A6   D0280PA00X+003327Y+136878               S0      
317LAN2_P3_N        J25   -A4   D0280PA00X+003327Y+137665               S0      
317GND              J25   -A2   D0280PA00X+003327Y+138453               S0      
317N/C              J28   -11   D0360PA00X+005150Y+157181               S0      
317LAN2_P2_N        J28   -6    D0360PA00X+004400Y+162299               S0      
317LAN2_P3_P        J28   -4    D0360PA00X+003400Y+162299               S0      
317LAN2_P4_P        J28   -7    D0360PA00X+004900Y+161299               S0      
317LAN2_P3_N        J28   -5    D0360PA00X+003900Y+161299               S0      
317LAN2_P2_P        J28   -3    D0360PA00X+002900Y+161299               S0      
317FAN4_TACH        J20   -10   D0570PA00X+004506Y+166887               S0      
317P12V             J20   -9    D0570PA00X+004506Y+168541               S0      
317P12V             J20   -8    D0570PA00X+004506Y+170195               S0      
317FAN3_TACH        J20   -7    D0570PA00X+004506Y+171848               S0      
317P12V             J20   -6    D0570PA00X+004506Y+173502               S0      
317P12V             J20   -5    D0570PA00X+004506Y+175155               S0      
317FAN2_TACH        J20   -4    D0570PA00X+004506Y+176809               S0      
317P12V             J20   -3    D0570PA00X+004506Y+178462               S0      
317FAN1_TACH        J20   -1    D0570PA00X+004506Y+181769               S0      
317P12V             J20   -2    D0570PA00X+004506Y+180116               S0      
317UART_TX_RP5_L    J22   -6    D0390PA00X+004274Y+195729               S0      
317NNAME10015       J22   -4    D0390PA00X+003274Y+195729               S0      
317NNAME10016       J22   -7    D0390PA00X+004774Y+194729               S0      
317GND              J22   -5    D0390PA00X+003774Y+194729               S0      
317UART_TX_RP6_L    J24   -6    D0390PA00X+004274Y+206166               S0      
317NNAME10025       J24   -4    D0390PA00X+003274Y+206166               S0      
317NNAME10026       J24   -7    D0390PA00X+004774Y+205166               S0      
317GND              J24   -5    D0390PA00X+003774Y+205166               S0      
317GND              VIA   -     D0100PA00X+002683Y+206787               S3      
317N/C              J19   -H1   D1320UA00X+005774Y+005995               S0      
317NNAME10012       J19   -1    D0390PA00X+005274Y+003495               S0      
317GND              H11   -6    D0220PA00X+006535Y+010118               S0      
317GND              H11   -5    D0220PA00X+005551Y+010512               S0      
317GND              H11   -4    D0220PA00X+005157Y+011496               S0      
317GND              H11   -3    D0220PA00X+005551Y+012480               S0      
317GND              H11   -2    D0220PA00X+006535Y+012874               S0      
317N/C              H11   -1    D1580UA00X+006535Y+011496               S0      
317N/C              J21   -H2   D1320UA00X+005774Y+018198               S0      
317NNAME10009       J21   -8    D0390PA00X+005274Y+021698               S0      
317NNAME10014       J23   -1    D0390PA00X+005274Y+024381               S0      
317N/C              J23   -H1   D1320UA00X+005774Y+026881               S0      
317N/C              J27   -H2   D1320UA00X+005774Y+039083               S0      
317NNAME10011       J27   -8    D0390PA00X+005274Y+042583               S0      
317GND              H10   -6    D0220PA00X+006535Y+045118               S0      
317GND              H10   -5    D0220PA00X+005551Y+045512               S0      
317GND              H10   -4    D0220PA00X+005157Y+046496               S0      
317N/C              H10   -1    D1580UA00X+006535Y+046496               S0      
317GND              H10   -3    D0220PA00X+005551Y+047480               S0      
317GND              H10   -2    D0220PA00X+006535Y+047874               S0      
317N/C              J29   -H1   D1260UA00X+005900Y+054370               S0      
317GND              J29   -G1   D0630PA00X+006750Y+052854               S0      
317LAN1_P1_P        J29   -1    D0360PA00X+005400Y+051870               S0      
317N42126764        J29   -9    D0360PA00X+006130Y+055988               S0      
327GND              R148  -2          A01X+005875Y+057702X0180Y0200R270 S2      
327N42126673        R148  -1          A01X+005875Y+057387X0180Y0200R270 S2      
327GND              R149  -2          A01X+006382Y+057708X0180Y0200R270 S2      
327N42126764        R149  -1          A01X+006382Y+057393X0180Y0200R270 S2      
317GND              VIA   -     D0100PA00X+005875Y+057965               S3      
317GND              VIA   -     D0100PA00X+006382Y+057965               S3      
317GND              VIA   -     D0100PA00X+006189Y+066601               S1      
317GND61            VIA   -     D0100PA00X+005712Y+067533               S1      
317GND29            VIA   -     D0100PA00X+005448Y+067981               S1      
317GND28            VIA   -     D0100PA00X+005924Y+067076               S1      
317GND              H2    -6    D0220PA00X+006535Y+080118               S0      
317GND              H2    -5    D0220PA00X+005551Y+080512               S0      
317GND              H2    -4    D0220PA00X+005157Y+081496               S0      
317GND              H2    -3    D0220PA00X+005551Y+082480               S0      
317GND              H2    -2    D0220PA00X+006535Y+082874               S0      
317N/C              H2    -1    D1580UA00X+006535Y+081496               S0      
317PSU6_DC_OK       VIA   -     D0100PA00X+007087Y+085428               S1      
327N/C                    -1          A01X+005634Y+087876X0390Y0390     S2      
327N/C                    -1          A08X+005516Y+088228X0390Y0390     S1      
317PSU5_AC_OK       VIA   -     D0100PA00X+007087Y+087228               S1      
317PSU6_AC_OK       VIA   -     D0100PA00X+007087Y+086628               S1      
317PSU4_DC_OK       VIA   -     D0100PA00X+007087Y+086028               S1      
317PSU2_PS_ON_N     VIA   -     D0100PA00X+007087Y+089775               S1      
317PSU4_AC_OK       VIA   -     D0100PA00X+007087Y+089012               S1      
317NNAME10027       VIA   -     D0100PA00X+006082Y+101903               S3      
317NNAME10028       VIA   -     D0100PA00X+006358Y+101912               S3      
317GND              H4    -6    D0220PA00X+006535Y+115118               S0      
317GND              H4    -5    D0220PA00X+005551Y+115512               S0      
317GND              H4    -4    D0220PA00X+005157Y+116496               S0      
317N/C              H4    -1    D1580UA00X+006535Y+116496               S0      
317GND              H4    -3    D0220PA00X+005551Y+117480               S0      
317GND              H4    -2    D0220PA00X+006535Y+117874               S0      
327GND              R140  -2          A01X+005441Y+125338X0180Y0200R180 S2      
327FAN_PWM          R140  -1          A01X+005126Y+125338X0180Y0200R180 S2      
327P12V             R144  -2          A01X+005421Y+126310X0180Y0200R180 S2      
327FAN3_TACH        R144  -1          A01X+005106Y+126310X0180Y0200R180 S2      
327P12V             R141  -2          A01X+005428Y+125763X0180Y0200R180 S2      
327FAN_PWM          R141  -1          A01X+005113Y+125763X0180Y0200R180 S2      
317P12V             VIA   -     D0100PA00X+005913Y+125765               S3      
317GND              VIA   -     D0100PA00X+005746Y+125338               S3      
327P12V             R142  -2          A01X+005458Y+127978X0180Y0200R180 S2      
327FAN1_TACH        R142  -1          A01X+005143Y+127978X0180Y0200R180 S2      
327P12V             R143  -2          A01X+005455Y+126729X0180Y0200R180 S2      
327FAN2_TACH        R143  -1          A01X+005140Y+126729X0180Y0200R180 S2      
327P12V             R145  -2          A01X+005445Y+128404X0180Y0200R180 S2      
327FAN4_TACH        R145  -1          A01X+005130Y+128404X0180Y0200R180 S2      
327P12V             R146  -2          A01X+005458Y+127563X0180Y0200R180 S2      
327FAN5_TACH        R146  -1          A01X+005143Y+127563X0180Y0200R180 S2      
327P12V             R147  -2          A01X+005448Y+127154X0180Y0200R180 S2      
327FAN6_TACH        R147  -1          A01X+005133Y+127154X0180Y0200R180 S2      
317P12V             VIA   -     D0100PA00X+005836Y+127981               S3      
317P12V             VIA   -     D0100PA00X+005842Y+127238               S3      
327FRU_A1           R35   -2          A01X+005875Y+130275X0180Y0200R270 S2      
327P3V3             R35   -1          A01X+005875Y+129960X0180Y0200R270 S2      
327FRU_A2           R36   -2          A01X+007191Y+130258X0180Y0200R270 S2      
327P3V3             R36   -1          A01X+007191Y+129943X0180Y0200R270 S2      
327FRU_A0           R34   -2          A01X+005033Y+130268X0180Y0200R270 S2      
327P3V3             R34   -1          A01X+005033Y+129953X0180Y0200R270 S2      
327FRU_A0           R37   -2          A01X+005454Y+130268X0180Y0200R270 S2      
327GND              R37   -1          A01X+005454Y+129953X0180Y0200R270 S2      
327FRU_A1           R38   -2          A01X+006306Y+130275X0180Y0200R270 S2      
327GND              R38   -1          A01X+006306Y+129960X0180Y0200R270 S2      
327FRU_A2           R39   -2          A01X+006757Y+130258X0180Y0200R270 S2      
327GND              R39   -1          A01X+006757Y+129943X0180Y0200R270 S2      
327GND              U1    -4          A01X+007187Y+131530X0220Y0680     S2      
327FRU_A2           U1    -3          A01X+006687Y+131530X0220Y0680     S2      
327FRU_A1           U1    -2          A01X+006187Y+131530X0220Y0680     S2      
327FRU_A0           U1    -1          A01X+005687Y+131530X0220Y0680     S2      
317GND              VIA   -     D0100PA00X+005454Y+129651               S3      
317GND              VIA   -     D0100PA00X+006306Y+129631               S3      
317GND              VIA   -     D0100PA00X+006757Y+129665               S3      
317FRU_A1           VIA   -     D0100PA00X+006187Y+130919               S1      
317FRU_A2           VIA   -     D0100PA00X+006757Y+130783               S1      
317FRU_A0           VIA   -     D0100PA00X+005454Y+130900               S1      
327P3V3             R41   -1          A01X+005296Y+133608X0180Y0200R270 S2      
327P3V3             U1    -8          A01X+005687Y+133610X0220Y0680     S2      
327FRU_WP           U1    -7          A01X+006187Y+133610X0220Y0680     S2      
327I2C_PDB_SCL      U1    -6          A01X+006687Y+133610X0220Y0680     S2      
327I2C_PDB_SDA      U1    -5          A01X+007187Y+133610X0220Y0680     S2      
327FRU_WP           R41   -2          A01X+005296Y+133923X0180Y0200R270 S2      
317FRU_WP           VIA   -     D0100PA00X+006187Y+134210               S1      
317GND              H6    -6    D0220PA00X+006535Y+150118               S0      
317GND              H6    -5    D0220PA00X+005551Y+150512               S0      
317GND              H6    -4    D0220PA00X+005157Y+151496               S0      
317GND              H6    -3    D0220PA00X+005551Y+152480               S0      
317GND              H6    -2    D0220PA00X+006535Y+152874               S0      
317N/C              H6    -1    D1580UA00X+006535Y+151496               S0      
327N42132358        R153  -2          A01X+006128Y+155914X0180Y0200R180 S2      
327GND              R153  -1          A01X+005813Y+155914X0180Y0200R180 S2      
317N42132358        J28   -12   D0360PA00X+006130Y+157181               S0      
317GND              VIA   -     D0100PA00X+005411Y+155914               S3      
317N/C              J28   -H2   D1260UA00X+005900Y+158799               S0      
317GND              J28   -G2   D0630PA00X+006750Y+160315               S0      
317LAN2_P4_N        J28   -8    D0360PA00X+005400Y+162299               S0      
317GND              H8    -6    D0220PA00X+006535Y+185118               S0      
317GND              H8    -5    D0220PA00X+005551Y+185512               S0      
317GND              H8    -4    D0220PA00X+005157Y+186496               S0      
317N/C              H8    -1    D1580UA00X+006535Y+186496               S0      
317GND              H8    -3    D0220PA00X+005551Y+187480               S0      
317GND              H8    -2    D0220PA00X+006535Y+187874               S0      
317N/C              J22   -H2   D1320UA00X+005774Y+192229               S0      
317NNAME10019       J22   -8    D0390PA00X+005274Y+195729               S0      
317N/C              J24   -H2   D1320UA00X+005774Y+202666               S0      
317NNAME10018       J24   -8    D0390PA00X+005274Y+206166               S0      
317GND              VIA   -     D0100PA00X+007522Y+001875               S3      
317GND              VIA   -     D0100PA00X+009742Y+003285               S3      
317GND              VIA   -     D0100PA00X+009742Y+003744               S3      
317GND              H11   -7    D0220PA00X+007520Y+010512               S0      
317GND              H11   -9    D0220PA00X+007520Y+012480               S0      
317GND              H11   -8    D0220PA00X+007913Y+011496               S0      
317GND              VIA   -     D0100PA00X+009754Y+037658               S3      
317GND              VIA   -     D0100PA00X+009746Y+037191               S3      
317GND              VIA   -     D0100PA00X+009799Y+039122               S3      
317GND              VIA   -     D0100PA00X+009764Y+039602               S3      
317PSU2_AC_OK       VIA   -     D0100PA00X+009322Y+041774               S3      
317PSU2_DC_OK       VIA   -     D0100PA00X+009435Y+042156               S3      
317GND              H10   -8    D0220PA00X+007913Y+046496               S0      
317GND              H10   -7    D0220PA00X+007520Y+045512               S0      
317GND              H10   -9    D0220PA00X+007520Y+047480               S0      
317GND              VIA   -     D0100PA00X+009859Y+072075               S3      
317GND              VIA   -     D0100PA00X+009856Y+071594               S3      
317GND              VIA   -     D0100PA00X+009744Y+073996               S3      
317GND              VIA   -     D0100PA00X+009753Y+073525               S3      
317GND              VIA   -     D0100PA00X+009812Y+074514               S3      
317PSU3_DC_OK       VIA   -     D0100PA00X+009578Y+075147               S1      
317GND              H2    -7    D0220PA00X+007520Y+080512               S0      
317GND              H2    -9    D0220PA00X+007520Y+082480               S0      
317GND              H2    -8    D0220PA00X+007913Y+081496               S0      
317I2C_PSU1_SCL     VIA   -     D0100PA00X+009222Y+089987               S1      
317PSU3_AC_OK       VIA   -     D0100PA00X+009071Y+087862               S1      
317I2C_PSU1_SDA     VIA   -     D0100PA00X+009263Y+090740               S1      
317PSU_ALERT_N      VIA   -     D0100PA00X+009299Y+092733               S1      
317I2C_PSU2_SDA     VIA   -     D0100PA00X+009814Y+099096               S1      
317NNAME10029       VIA   -     D0100PA00X+007645Y+101487               S3      
317NNAME10030       VIA   -     D0100PA00X+007950Y+101487               S3      
317GND              VIA   -     D0100PA00X+009690Y+106752               S3      
317T7_BLAD2_RXD     VIA   -     D0100PA00X+008276Y+106005               S1      
317GND              VIA   -     D0100PA00X+009695Y+109204               S3      
317GND              VIA   -     D0100PA00X+009695Y+108710               S3      
317GND              VIA   -     D0100PA00X+009677Y+107223               S3      
317P12V_STBY        VIA   -     D0100PA00X+009668Y+108179               S1      
317GND              H4    -8    D0220PA00X+007913Y+116496               S0      
317GND              H4    -7    D0220PA00X+007520Y+115512               S0      
317GND              H4    -9    D0220PA00X+007520Y+117480               S0      
317GND              VIA   -     D0100PA00X+007548Y+131530               S3      
317T9_BLAD1_EN      VIA   -     D0100PA00X+009651Y+139538               S1      
317GND              VIA   -     D0100PA00X+009740Y+142434               S3      
317GND              VIA   -     D0100PA00X+009783Y+141949               S3      
317GND              VIA   -     D0100PA00X+009699Y+144374               S3      
317GND              VIA   -     D0100PA00X+009700Y+143898               S3      
317GND              VIA   -     D0100PA00X+009747Y+144792               S3      
317PSU_CSAHRE       VIA   -     D0100PA00X+009524Y+145332               S3      
317GND              H6    -7    D0220PA00X+007520Y+150512               S0      
317GND              H6    -9    D0220PA00X+007520Y+152480               S0      
317GND              H6    -8    D0220PA00X+007913Y+151496               S0      
317GND              H8    -8    D0220PA00X+007913Y+186496               S0      
317GND              H8    -7    D0220PA00X+007520Y+185512               S0      
317GND              H8    -9    D0220PA00X+007520Y+187480               S0      
317GND              VIA   -     D0100PA00X+007683Y+206787               S3      
317PSU_ALERT_N      J1    -32   D0440PA00X+011992Y+001807               S0      
317PSU1_RESET       J1    -31   D0440PA00X+011992Y+002807               S0      
327GND              R45   -2          A01X+010585Y+002008X0180Y0200     S2      
327PSU1_RESET       R45   -1          A01X+010900Y+002008X0180Y0200     S2      
327P12V_STBY        R62   -2          A01X+010078Y+002832X0180Y0200     S2      
327PSU1_PS_KILL     R62   -1          A01X+010393Y+002832X0180Y0200     S2      
327P12V_STBY        R64   -2          A01X+010069Y+002420X0180Y0200     S2      
327PSU1_RESET       R64   -1          A01X+010384Y+002420X0180Y0200     S2      
327GND              R65   -2          A01X+010585Y+001585X0180Y0200     S2      
327PSU1_RESET       R65   -1          A01X+010900Y+001585X0180Y0200     S2      
317GND              VIA   -     D0100PA00X+010634Y+002258               S3      
317PSU1_RESET       VIA   -     D0100PA00X+010696Y+002629               S1      
317PSU1_PS_KILL     J1    -30   D0440PA00X+011992Y+003807               S0      
317PSU1_PS_ON_N     J1    -29   D0440PA00X+011992Y+004807               S0      
317PSU1_CSAHRE      J1    -28   D0440PA00X+011992Y+005807               S0      
327PSU1_PS_ON_N     R49   -2          A01X+010809Y+004629X0180Y0200R180 S2      
327GND              R49   -1          A01X+010494Y+004629X0180Y0200R180 S2      
327PSU2_PS_ON_N     R50   -2          A01X+010493Y+004180X0180Y0200     S2      
327GND              R50   -1          A01X+010808Y+004180X0180Y0200     S2      
327GND              R43   -2          A01X+010078Y+003285X0180Y0200     S2      
327PSU1_PS_KILL     R43   -1          A01X+010393Y+003285X0180Y0200     S2      
327GND              R63   -2          A01X+010078Y+003744X0180Y0200     S2      
327PSU1_PS_KILL     R63   -1          A01X+010393Y+003744X0180Y0200     S2      
317GND              VIA   -     D0100PA00X+010808Y+003890               S3      
317GND              VIA   -     D0100PA00X+010265Y+004946               S3      
317PSU2_PS_ON_N     VIA   -     D0100PA00X+010143Y+004180               S3      
317PSU1_PS_ON_N     VIA   -     D0100PA00X+010741Y+004990               S1      
317PSU1_PS_KILL     VIA   -     D0100PA00X+010704Y+003469               S1      
317PSU1_AC_OK       J1    -27   D0440PA00X+011992Y+006807               S0      
317PSU1_REMOTE_N    J1    -26   D0440PA00X+011992Y+007807               S0      
327GND              R5    -2          A01X+010414Y+007819X0180Y0200     S2      
327PSU1_REMOTE_N    R5    -1          A01X+010729Y+007819X0180Y0200     S2      
327PSU1_REMOTE_N    R87   -1          A01X+010727Y+007821X0180Y0200R270 S2      
327NNAME10031       R113  -2          A01X+010726Y+007506X0180Y0200R090 S2      
327PSU1_REMOTE_N    R113  -1          A01X+010726Y+007821X0180Y0200R090 S2      
327PSU_CSAHRE       R134  -2          A01X+010273Y+005825X0180Y0200     S2      
327PSU1_CSAHRE      R134  -1          A01X+010588Y+005825X0180Y0200     S2      
317PSU_CSAHRE       VIA   -     D0100PA00X+010435Y+006229               S3      
317NNAME10031       VIA   -     D0100PA00X+010726Y+007224               S3      
317PSU1_CSAHRE      VIA   -     D0100PA00X+010905Y+005825               S3      
317N/C              J1    -25   D0440PA00X+011992Y+008807               S0      
317GND              J1    -24   D0440PA00X+011992Y+009807               S0      
327NNAME10032       R87   -2          A01X+010727Y+008136X0180Y0200R270 S2      
317GND              VIA   -     D0100PA00X+010412Y+008256               S3      
317NNAME10032       VIA   -     D0100PA00X+010721Y+008517               S3      
317GND              J1    -23   D0440PA00X+011992Y+010807               S0      
317GND              J1    -22   D0440PA00X+011992Y+011807               S0      
317GND              J1    -21   D0440PA00X+011992Y+012807               S0      
317GND              J1    -20   D0440PA00X+011992Y+013807               S0      
317GND              J1    -19   D0440PA00X+011992Y+014807               S0      
317GND              J1    -18   D0440PA00X+011992Y+015807               S0      
317GND              J1    -17   D0440PA00X+011992Y+016807               S0      
317GND              J1    -16   D0440PA00X+011992Y+017807               S0      
317GND              J1    -15   D0440PA00X+011992Y+018807               S0      
317GND              J1    -14   D0440PA00X+011992Y+019807               S0      
317GND              J1    -13   D0440PA00X+011992Y+020807               S0      
317P12V             J1    -12   D0440PA00X+011992Y+021807               S0      
317P12V             J1    -11   D0440PA00X+011992Y+022807               S0      
317P12V             J1    -10   D0440PA00X+011992Y+023807               S0      
317P12V             J1    -9    D0440PA00X+011992Y+024807               S0      
317P12V             J1    -8    D0440PA00X+011992Y+025807               S0      
317P12V             J1    -7    D0440PA00X+011992Y+026807               S0      
317P12V             J1    -6    D0440PA00X+011992Y+027807               S0      
317P12V             J1    -5    D0440PA00X+011992Y+028807               S0      
317P12V             J1    -4    D0440PA00X+011992Y+029807               S0      
317P12V             J1    -3    D0440PA00X+011992Y+030807               S0      
317P12V             J1    -2    D0440PA00X+011992Y+031807               S0      
317P12V             J1    -1    D0440PA00X+011992Y+032807               S0      
317PSU_ALERT_N      J2    -32   D0440PA00X+011992Y+036610               S0      
317PSU2_RESET       J2    -31   D0440PA00X+011992Y+037610               S0      
317PSU2_PS_KILL     J2    -30   D0440PA00X+011992Y+038610               S0      
317PSU2_PS_ON_N     J2    -29   D0440PA00X+011992Y+039610               S0      
327GND              R46   -2          A01X+010052Y+039122X0180Y0200     S2      
327PSU2_PS_KILL     R46   -1          A01X+010367Y+039122X0180Y0200     S2      
327GND              R47   -2          A01X+010052Y+037658X0180Y0200     S2      
327PSU2_RESET       R47   -1          A01X+010367Y+037658X0180Y0200     S2      
327P12V_STBY        R66   -2          A01X+010052Y+038624X0180Y0200     S2      
327PSU2_PS_KILL     R66   -1          A01X+010367Y+038624X0180Y0200     S2      
327P12V_STBY        R68   -2          A01X+010052Y+038139X0180Y0200     S2      
327PSU2_RESET       R68   -1          A01X+010367Y+038139X0180Y0200     S2      
327GND              R69   -2          A01X+010052Y+037191X0180Y0200     S2      
327PSU2_RESET       R69   -1          A01X+010367Y+037191X0180Y0200     S2      
317PSU2_RESET       VIA   -     D0100PA00X+010684Y+037646               S1      
317PSU2_PS_KILL     VIA   -     D0100PA00X+010671Y+039122               S1      
317PSU2_CSAHRE      J2    -28   D0440PA00X+011992Y+040610               S0      
317PSU2_AC_OK       J2    -27   D0440PA00X+011992Y+041610               S0      
327GND              R67   -2          A01X+010052Y+039602X0180Y0200     S2      
327PSU2_PS_KILL     R67   -1          A01X+010367Y+039602X0180Y0200     S2      
327PSU_CSAHRE       R135  -2          A01X+010079Y+040035X0180Y0200     S2      
327PSU2_CSAHRE      R135  -1          A01X+010394Y+040035X0180Y0200     S2      
317PSU_CSAHRE       VIA   -     D0100PA00X+010545Y+040680               S3      
317PSU2_PS_ON_N     VIA   -     D0100PA00X+011450Y+039621               S3      
317PSU2_REMOTE_N    J2    -26   D0440PA00X+011992Y+042610               S0      
317N/C              J2    -25   D0440PA00X+011992Y+043610               S0      
327GND              R7    -2          A01X+010452Y+042610X0180Y0200     S2      
327PSU2_REMOTE_N    R7    -1          A01X+010767Y+042610X0180Y0200     S2      
327NNAME10033       R93   -2          A01X+010767Y+042925X0180Y0200R270 S2      
327PSU2_REMOTE_N    R93   -1          A01X+010767Y+042610X0180Y0200R270 S2      
327NNAME10034       R117  -2          A01X+010767Y+042295X0180Y0200R090 S2      
327PSU2_REMOTE_N    R117  -1          A01X+010767Y+042610X0180Y0200R090 S2      
317GND              VIA   -     D0100PA00X+010199Y+042610               S3      
317NNAME10033       VIA   -     D0100PA00X+010948Y+043474               S3      
317NNAME10034       VIA   -     D0100PA00X+011102Y+041957               S3      
317GND              J2    -24   D0440PA00X+011992Y+044610               S0      
317GND              J2    -23   D0440PA00X+011992Y+045610               S0      
317GND              J2    -22   D0440PA00X+011992Y+046610               S0      
317GND              J2    -21   D0440PA00X+011992Y+047610               S0      
317GND              J2    -20   D0440PA00X+011992Y+048610               S0      
317GND              J2    -19   D0440PA00X+011992Y+049610               S0      
317GND              J2    -18   D0440PA00X+011992Y+050610               S0      
317GND              J2    -17   D0440PA00X+011992Y+051610               S0      
317GND              J2    -16   D0440PA00X+011992Y+052610               S0      
317GND              J2    -15   D0440PA00X+011992Y+053610               S0      
317GND              J2    -14   D0440PA00X+011992Y+054610               S0      
317GND              J2    -13   D0440PA00X+011992Y+055610               S0      
317P12V             J2    -12   D0440PA00X+011992Y+056610               S0      
317P12V             J2    -11   D0440PA00X+011992Y+057610               S0      
317P12V             J2    -10   D0440PA00X+011992Y+058610               S0      
317P12V             J2    -9    D0440PA00X+011992Y+059610               S0      
317P12V             J2    -8    D0440PA00X+011992Y+060610               S0      
317P12V             J2    -7    D0440PA00X+011992Y+061610               S0      
317P12V             J2    -6    D0440PA00X+011992Y+062610               S0      
317P12V             J2    -5    D0440PA00X+011992Y+063610               S0      
317P12V             J2    -4    D0440PA00X+011992Y+064610               S0      
317P12V             J2    -3    D0440PA00X+011992Y+065610               S0      
317P12V             J2    -2    D0440PA00X+011992Y+066610               S0      
317P12V             J2    -1    D0440PA00X+011992Y+067610               S0      
317PSU_ALERT_N      J3    -32   D0440PA00X+011992Y+071413               S0      
317PSU3_RESET       J3    -31   D0440PA00X+011992Y+072413               S0      
317PSU3_PS_KILL     J3    -30   D0440PA00X+011992Y+073413               S0      
327GND              R55   -2          A01X+010106Y+072075X0180Y0200     S2      
327PSU3_RESET       R55   -1          A01X+010421Y+072075X0180Y0200     S2      
327P12V_STBY        R70   -2          A01X+010106Y+073040X0180Y0200     S2      
327PSU3_PS_KILL     R70   -1          A01X+010421Y+073040X0180Y0200     S2      
327P12V_STBY        R72   -2          A01X+010106Y+072546X0180Y0200     S2      
327PSU3_RESET       R72   -1          A01X+010421Y+072546X0180Y0200     S2      
327GND              R73   -2          A01X+010106Y+071594X0180Y0200     S2      
327PSU3_RESET       R73   -1          A01X+010421Y+071594X0180Y0200     S2      
317PSU3_RESET       VIA   -     D0100PA00X+010703Y+072537               S1      
317PSU3_PS_ON_N     J3    -29   D0440PA00X+011992Y+074413               S0      
317PSU3_CSAHRE      J3    -28   D0440PA00X+011992Y+075413               S0      
327PSU3_PS_ON_N     R51   -2          A01X+010435Y+074514X0180Y0200R180 S2      
327GND              R51   -1          A01X+010120Y+074514X0180Y0200R180 S2      
327GND              R48   -2          A01X+010106Y+073525X0180Y0200     S2      
327PSU3_PS_KILL     R48   -1          A01X+010421Y+073525X0180Y0200     S2      
327GND              R71   -2          A01X+010106Y+073996X0180Y0200     S2      
327PSU3_PS_KILL     R71   -1          A01X+010421Y+073996X0180Y0200     S2      
327PSU_CSAHRE       R136  -2          A01X+010152Y+074948X0180Y0200     S2      
327PSU3_CSAHRE      R136  -1          A01X+010467Y+074948X0180Y0200     S2      
317PSU_CSAHRE       VIA   -     D0100PA00X+010509Y+075413               S3      
317PSU3_PS_ON_N     VIA   -     D0100PA00X+010694Y+074514               S1      
317PSU3_PS_KILL     VIA   -     D0100PA00X+010717Y+073522               S1      
317PSU3_AC_OK       J3    -27   D0440PA00X+011992Y+076413               S0      
317PSU3_REMOTE_N    J3    -26   D0440PA00X+011992Y+077413               S0      
327GND              R6    -2          A01X+010444Y+077410X0180Y0200     S2      
327PSU3_REMOTE_N    R6    -1          A01X+010759Y+077410X0180Y0200     S2      
327NNAME10035       R97   -2          A01X+010762Y+077730X0180Y0200R270 S2      
327PSU3_REMOTE_N    R97   -1          A01X+010762Y+077415X0180Y0200R270 S2      
327NNAME10036       R121  -2          A01X+010762Y+077100X0180Y0200R090 S2      
327PSU3_REMOTE_N    R121  -1          A01X+010762Y+077415X0180Y0200R090 S2      
317GND              VIA   -     D0100PA00X+010124Y+077410               S3      
317NNAME10036       VIA   -     D0100PA00X+011284Y+076912               S3      
317N/C              J3    -25   D0440PA00X+011992Y+078413               S0      
317GND              J3    -24   D0440PA00X+011992Y+079413               S0      
317GND              J3    -23   D0440PA00X+011992Y+080413               S0      
317NNAME10035       VIA   -     D0100PA00X+011370Y+079429               S3      
317GND              J3    -22   D0440PA00X+011992Y+081413               S0      
317GND              J3    -21   D0440PA00X+011992Y+082413               S0      
317GND              J3    -20   D0440PA00X+011992Y+083413               S0      
317GND              J3    -19   D0440PA00X+011992Y+084413               S0      
317GND              J3    -18   D0440PA00X+011992Y+085413               S0      
317GND              J3    -17   D0440PA00X+011992Y+086413               S0      
317GND              J3    -16   D0440PA00X+011992Y+087413               S0      
317GND              J3    -15   D0440PA00X+011992Y+088413               S0      
317GND              J3    -14   D0440PA00X+011992Y+089413               S0      
317GND              J3    -13   D0440PA00X+011992Y+090413               S0      
317P12V             J3    -12   D0440PA00X+011992Y+091413               S0      
317P12V             J3    -11   D0440PA00X+011992Y+092413               S0      
317P12V             J3    -10   D0440PA00X+011992Y+093413               S0      
317P12V             J3    -9    D0440PA00X+011992Y+094413               S0      
317P12V             J3    -8    D0440PA00X+011992Y+095413               S0      
317P12V             J3    -7    D0440PA00X+011992Y+096413               S0      
317P12V             J3    -6    D0440PA00X+011992Y+097413               S0      
317NNAME10037       VIA   -     D0100PA00X+010540Y+097204               S3      
317NNAME10035       VIA   -     D0100PA00X+010261Y+097222               S3      
317P12V             J3    -5    D0440PA00X+011992Y+098413               S0      
317P12V             J3    -4    D0440PA00X+011992Y+099413               S0      
317P12V             J3    -3    D0440PA00X+011992Y+100413               S0      
317P12V             J3    -2    D0440PA00X+011992Y+101413               S0      
317P12V             J3    -1    D0440PA00X+011992Y+102413               S0      
317I2C_PSU2_SCL     VIA   -     D0100PA00X+010069Y+099939               S1      
317PSU_ALERT_N      J4    -32   D0440PA00X+011992Y+106217               S0      
317PSU4_RESET       J4    -31   D0440PA00X+011992Y+107217               S0      
327GND              R77   -2          A01X+010119Y+106752X0180Y0200     S2      
327PSU4_RESET       R77   -1          A01X+010434Y+106752X0180Y0200     S2      
317PSU4_PS_KILL     J4    -30   D0440PA00X+011992Y+108217               S0      
317PSU4_PS_ON_N     J4    -29   D0440PA00X+011992Y+109217               S0      
327GND              R56   -2          A01X+010119Y+109204X0180Y0200     S2      
327PSU4_PS_KILL     R56   -1          A01X+010434Y+109204X0180Y0200     S2      
327GND              R57   -2          A01X+010119Y+107223X0180Y0200     S2      
327PSU4_RESET       R57   -1          A01X+010434Y+107223X0180Y0200     S2      
327P12V_STBY        R74   -2          A01X+010119Y+108179X0180Y0200     S2      
327PSU4_PS_KILL     R74   -1          A01X+010434Y+108179X0180Y0200     S2      
327P12V_STBY        R76   -2          A01X+010119Y+107690X0180Y0200     S2      
327PSU4_RESET       R76   -1          A01X+010434Y+107690X0180Y0200     S2      
327GND              R75   -2          A01X+010119Y+108710X0180Y0200     S2      
327PSU4_PS_KILL     R75   -1          A01X+010434Y+108710X0180Y0200     S2      
317PSU4_PS_ON_N     VIA   -     D0100PA00X+010735Y+109348               S1      
317PSU4_PS_KILL     VIA   -     D0100PA00X+010724Y+108179               S1      
317PSU4_RESET       VIA   -     D0100PA00X+010722Y+107221               S1      
317PSU4_CSAHRE      J4    -28   D0440PA00X+011992Y+110217               S0      
317PSU4_AC_OK       J4    -27   D0440PA00X+011992Y+111217               S0      
317PSU4_REMOTE_N    J4    -26   D0440PA00X+011992Y+112217               S0      
327PSU4_PS_ON_N     R52   -2          A01X+010443Y+109640X0180Y0200R180 S2      
327GND              R52   -1          A01X+010128Y+109640X0180Y0200R180 S2      
327NNAME10038       R125  -2          A01X+010882Y+111902X0180Y0200R090 S2      
327PSU_CSAHRE       R137  -2          A01X+010588Y+110254X0180Y0200     S2      
327PSU4_CSAHRE      R137  -1          A01X+010903Y+110254X0180Y0200     S2      
317GND              VIA   -     D0100PA00X+009865Y+109640               S3      
317PSU_CSAHRE       VIA   -     D0100PA00X+010878Y+110576               S3      
317MATE_A1          VIA   -     D0100PA00X+010515Y+111838               S1      
317NNAME10038       VIA   -     D0100PA00X+011250Y+111586               S3      
317N/C              J4    -25   D0440PA00X+011992Y+113217               S0      
317GND              J4    -24   D0440PA00X+011992Y+114217               S0      
327GND              R20   -2          A01X+010568Y+112217X0180Y0200     S2      
327PSU4_REMOTE_N    R20   -1          A01X+010883Y+112217X0180Y0200     S2      
327NNAME10030       R109  -2          A01X+010882Y+112531X0180Y0200R270 S2      
327PSU4_REMOTE_N    R109  -1          A01X+010882Y+112216X0180Y0200R270 S2      
327PSU4_REMOTE_N    R125  -1          A01X+010882Y+112217X0180Y0200R090 S2      
317GND              VIA   -     D0100PA00X+010568Y+112592               S3      
317NNAME10030       VIA   -     D0100PA00X+010847Y+112929               S3      
317GND              J4    -23   D0440PA00X+011992Y+115217               S0      
317GND              J4    -22   D0440PA00X+011992Y+116217               S0      
317GND              J4    -21   D0440PA00X+011992Y+117217               S0      
317GND              J4    -20   D0440PA00X+011992Y+118217               S0      
317GND              J4    -19   D0440PA00X+011992Y+119217               S0      
317GND              J4    -18   D0440PA00X+011992Y+120217               S0      
317GND              J4    -17   D0440PA00X+011992Y+121217               S0      
317GND              J4    -16   D0440PA00X+011992Y+122217               S0      
317GND              J4    -15   D0440PA00X+011992Y+123217               S0      
317GND              J4    -14   D0440PA00X+011992Y+124217               S0      
317GND              J4    -13   D0440PA00X+011992Y+125217               S0      
317P12V             J4    -12   D0440PA00X+011992Y+126217               S0      
317P12V             J4    -11   D0440PA00X+011992Y+127217               S0      
317P12V             J4    -10   D0440PA00X+011992Y+128217               S0      
317P12V             J4    -9    D0440PA00X+011992Y+129217               S0      
317P12V             J4    -8    D0440PA00X+011992Y+130217               S0      
317P12V             J4    -7    D0440PA00X+011992Y+131217               S0      
317PSU_CSAHRE       VIA   -     D0100PA00X+010072Y+131281               S1      
317PSU6_DC_OK       VIA   -     D0100PA00X+010072Y+130681               S1      
317P12V             J4    -6    D0440PA00X+011992Y+132217               S0      
317P12V             J4    -5    D0440PA00X+011992Y+133217               S0      
317I2C_PSU3_SDA     VIA   -     D0100PA00X+010072Y+133081               S1      
317I2C_PSU3_SCL     VIA   -     D0100PA00X+010072Y+133681               S1      
317PSU_ALERT_N      VIA   -     D0100PA00X+010072Y+132481               S1      
317PSU5_DC_OK       VIA   -     D0100PA00X+010072Y+131881               S1      
317P12V             J4    -4    D0440PA00X+011992Y+134217               S0      
317P12V             J4    -3    D0440PA00X+011992Y+135217               S0      
317P12V             J4    -2    D0440PA00X+011992Y+136217               S0      
317PSU_CSAHRE       VIA   -     D0100PA00X+010072Y+134607               S1      
317P12V             J4    -1    D0440PA00X+011992Y+137217               S0      
317PSU_ALERT_N      J5    -32   D0440PA00X+011992Y+141020               S0      
317T9_BLAD2_EN      VIA   -     D0100PA00X+010163Y+139764               S1      
317PSU5_RESET       J5    -31   D0440PA00X+011992Y+142020               S0      
317PSU5_PS_KILL     J5    -30   D0440PA00X+011992Y+143020               S0      
327GND              R59   -2          A01X+010023Y+141949X0180Y0200     S2      
327PSU5_RESET       R59   -1          A01X+010338Y+141949X0180Y0200     S2      
327P12V_STBY        R80   -2          A01X+010023Y+142920X0180Y0200     S2      
327PSU5_RESET       R80   -1          A01X+010338Y+142920X0180Y0200     S2      
327GND              R81   -2          A01X+010023Y+142434X0180Y0200     S2      
327PSU5_RESET       R81   -1          A01X+010338Y+142434X0180Y0200     S2      
317PSU5_PS_KILL     VIA   -     D0100PA00X+010696Y+143404               S1      
317PSU5_RESET       VIA   -     D0100PA00X+010692Y+141949               S1      
317PSU5_PS_ON_N     J5    -29   D0440PA00X+011992Y+144020               S0      
317PSU5_CSAHRE      J5    -28   D0440PA00X+011992Y+145020               S0      
317PSU5_AC_OK       J5    -27   D0440PA00X+011992Y+146020               S0      
327PSU5_PS_ON_N     R53   -2          A01X+010344Y+144792X0180Y0200R180 S2      
327GND              R53   -1          A01X+010029Y+144792X0180Y0200R180 S2      
327GND              R58   -2          A01X+010023Y+144374X0180Y0200     S2      
327PSU5_PS_KILL     R58   -1          A01X+010338Y+144374X0180Y0200     S2      
327P12V_STBY        R78   -2          A01X+010023Y+143404X0180Y0200     S2      
327PSU5_PS_KILL     R78   -1          A01X+010338Y+143404X0180Y0200     S2      
327GND              R79   -2          A01X+010023Y+143898X0180Y0200     S2      
327PSU5_PS_KILL     R79   -1          A01X+010338Y+143898X0180Y0200     S2      
327PSU_CSAHRE       R138  -2          A01X+010002Y+145313X0180Y0200     S2      
327PSU5_CSAHRE      R138  -1          A01X+010317Y+145313X0180Y0200     S2      
317PSU5_PS_ON_N     VIA   -     D0100PA00X+010676Y+144460               S1      
317PSU5_CSAHRE      VIA   -     D0100PA00X+010701Y+145265               S1      
317PSU5_REMOTE_N    J5    -26   D0440PA00X+011992Y+147020               S0      
317N/C              J5    -25   D0440PA00X+011992Y+148020               S0      
327GND              R19   -2          A01X+010539Y+147021X0180Y0200     S2      
327PSU5_REMOTE_N    R19   -1          A01X+010854Y+147021X0180Y0200     S2      
327NNAME10039       R105  -2          A01X+010857Y+147336X0180Y0200R270 S2      
327PSU5_REMOTE_N    R105  -1          A01X+010857Y+147021X0180Y0200R270 S2      
327NNAME10040       R129  -2          A01X+010857Y+146706X0180Y0200R090 S2      
327PSU5_REMOTE_N    R129  -1          A01X+010857Y+147021X0180Y0200R090 S2      
317GND              VIA   -     D0100PA00X+010546Y+147289               S3      
317NNAME10040       VIA   -     D0100PA00X+010857Y+146339               S3      
317GND              J5    -24   D0440PA00X+011992Y+149020               S0      
317GND              J5    -23   D0440PA00X+011992Y+150020               S0      
317NNAME10039       VIA   -     D0100PA00X+011352Y+148957               S3      
317GND              J5    -22   D0440PA00X+011992Y+151020               S0      
317GND              J5    -21   D0440PA00X+011992Y+152020               S0      
317GND              J5    -20   D0440PA00X+011992Y+153020               S0      
317GND              J5    -19   D0440PA00X+011992Y+154020               S0      
317GND              J5    -18   D0440PA00X+011992Y+155020               S0      
317GND              J5    -17   D0440PA00X+011992Y+156020               S0      
317GND              J5    -16   D0440PA00X+011992Y+157020               S0      
317GND              J5    -15   D0440PA00X+011992Y+158020               S0      
317GND              J5    -14   D0440PA00X+011992Y+159020               S0      
317GND              J5    -13   D0440PA00X+011992Y+160020               S0      
317P12V             J5    -12   D0440PA00X+011992Y+161020               S0      
317P12V             J5    -11   D0440PA00X+011992Y+162020               S0      
317P12V             J5    -10   D0440PA00X+011992Y+163020               S0      
317P12V             J5    -9    D0440PA00X+011992Y+164020               S0      
317P12V             J5    -8    D0440PA00X+011992Y+165020               S0      
317P12V             J5    -7    D0440PA00X+011992Y+166020               S0      
317P12V             J5    -6    D0440PA00X+011992Y+167020               S0      
317P12V             J5    -5    D0440PA00X+011992Y+168020               S0      
317P12V             J5    -4    D0440PA00X+011992Y+169020               S0      
317P12V             J5    -3    D0440PA00X+011992Y+170020               S0      
317P12V             J5    -2    D0440PA00X+011992Y+171020               S0      
317P12V             J5    -1    D0440PA00X+011992Y+172020               S0      
317PSU_ALERT_N      J6    -32   D0440PA00X+011992Y+175823               S0      
317PSU6_RESET       J6    -31   D0440PA00X+011992Y+176823               S0      
327GND              R61   -2          A01X+010168Y+176083X0180Y0200     S2      
327PSU6_RESET       R61   -1          A01X+010483Y+176083X0180Y0200     S2      
327P12V_STBY        R84   -2          A01X+010168Y+177053X0180Y0200     S2      
327PSU6_RESET       R84   -1          A01X+010483Y+177053X0180Y0200     S2      
327GND              R85   -2          A01X+010168Y+176572X0180Y0200     S2      
327PSU6_RESET       R85   -1          A01X+010483Y+176572X0180Y0200     S2      
317GND              VIA   -     D0100PA00X+009910Y+176572               S3      
317GND              VIA   -     D0100PA00X+009907Y+176083               S3      
317PSU6_RESET       VIA   -     D0100PA00X+010736Y+177044               S1      
317PSU6_PS_KILL     J6    -30   D0440PA00X+011992Y+177823               S0      
317PSU6_PS_ON_N     J6    -29   D0440PA00X+011992Y+178823               S0      
317PSU6_CSAHRE      J6    -28   D0440PA00X+011992Y+179823               S0      
327PSU6_PS_ON_N     R54   -2          A01X+010493Y+178995X0180Y0200R180 S2      
327GND              R54   -1          A01X+010178Y+178995X0180Y0200R180 S2      
327GND              R60   -2          A01X+010168Y+178557X0180Y0200     S2      
327PSU6_PS_KILL     R60   -1          A01X+010483Y+178557X0180Y0200     S2      
327P12V_STBY        R82   -2          A01X+010168Y+177551X0180Y0200     S2      
327PSU6_PS_KILL     R82   -1          A01X+010483Y+177551X0180Y0200     S2      
327GND              R83   -2          A01X+010168Y+178054X0180Y0200     S2      
327PSU6_PS_KILL     R83   -1          A01X+010483Y+178054X0180Y0200     S2      
317GND              VIA   -     D0100PA00X+009905Y+178557               S3      
317GND              VIA   -     D0100PA00X+009887Y+178054               S3      
317GND              VIA   -     D0100PA00X+009929Y+178995               S3      
317PSU_CSAHRE       VIA   -     D0100PA00X+010739Y+179446               S3      
317PSU6_PS_ON_N     VIA   -     D0100PA00X+010722Y+179159               S1      
317PSU6_PS_KILL     VIA   -     D0100PA00X+010737Y+178054               S1      
317PSU6_AC_OK       J6    -27   D0440PA00X+011992Y+180823               S0      
317PSU6_REMOTE_N    J6    -26   D0440PA00X+011992Y+181823               S0      
327GND              R22   -2          A01X+010567Y+181823X0180Y0200     S2      
327PSU6_REMOTE_N    R22   -1          A01X+010882Y+181823X0180Y0200     S2      
327PSU6_REMOTE_N    R101  -1          A01X+010882Y+181823X0180Y0200R270 S2      
327NNAME10041       R133  -2          A01X+010882Y+181508X0180Y0200R090 S2      
327PSU6_REMOTE_N    R133  -1          A01X+010882Y+181823X0180Y0200R090 S2      
327PSU_CSAHRE       R139  -2          A01X+010367Y+179822X0180Y0200     S2      
327PSU6_CSAHRE      R139  -1          A01X+010682Y+179822X0180Y0200     S2      
317GND              VIA   -     D0100PA00X+010567Y+181523               S3      
317NNAME10041       VIA   -     D0100PA00X+010882Y+181212               S3      
317PSU6_CSAHRE      VIA   -     D0100PA00X+010682Y+180223               S1      
317N/C              J6    -25   D0440PA00X+011992Y+182823               S0      
317GND              J6    -24   D0440PA00X+011992Y+183823               S0      
327NNAME10028       R101  -2          A01X+010882Y+182138X0180Y0200R270 S2      
317NNAME10028       VIA   -     D0100PA00X+010882Y+182447               S3      
317GND              J6    -23   D0440PA00X+011992Y+184823               S0      
317GND              J6    -22   D0440PA00X+011992Y+185823               S0      
317GND              J6    -21   D0440PA00X+011992Y+186823               S0      
317GND              J6    -20   D0440PA00X+011992Y+187823               S0      
317GND              J6    -19   D0440PA00X+011992Y+188823               S0      
317GND              J6    -18   D0440PA00X+011992Y+189823               S0      
317GND              J6    -17   D0440PA00X+011992Y+190823               S0      
317GND              J6    -16   D0440PA00X+011992Y+191823               S0      
317GND              J6    -15   D0440PA00X+011992Y+192823               S0      
317GND              J6    -14   D0440PA00X+011992Y+193823               S0      
317GND              J6    -13   D0440PA00X+011992Y+194823               S0      
317P12V             J6    -12   D0440PA00X+011992Y+195823               S0      
317P12V             J6    -11   D0440PA00X+011992Y+196823               S0      
317P12V             J6    -10   D0440PA00X+011992Y+197823               S0      
317P12V             J6    -9    D0440PA00X+011992Y+198823               S0      
317P12V             J6    -8    D0440PA00X+011992Y+199823               S0      
317P12V             J6    -7    D0440PA00X+011992Y+200823               S0      
317P12V             J6    -6    D0440PA00X+011992Y+201823               S0      
317P12V             J6    -5    D0440PA00X+011992Y+202823               S0      
317P12V             J6    -4    D0440PA00X+011992Y+203823               S0      
317P12V             J6    -3    D0440PA00X+011992Y+204823               S0      
317P12V             J6    -2    D0440PA00X+011992Y+205823               S0      
317P12V             J6    -1    D0440PA00X+011992Y+206823               S0      
317GND              VIA   -     D0100PA00X+010999Y+208361               S3      
317GND              VIA   -     D0100PA00X+012522Y+000300               S3      
317N/C              J1    -34   D0440PA00X+013992Y+002807               S0      
317I2C_PSU1_SDA     J1    -33   D0440PA00X+013992Y+001807               S0      
317PSU1_DC_OK       J1    -37   D0440PA00X+013992Y+005807               S0      
317PSU1_RETURN      J1    -36   D0440PA00X+013992Y+004807               S0      
317I2C_PSU1_SCL     J1    -35   D0440PA00X+013992Y+003807               S0      
317P12V_STBY        J1    -39   D0440PA00X+013992Y+007807               S0      
317PSU1_AD0         J1    -38   D0440PA00X+013992Y+006807               S0      
317GND              J1    -41   D0440PA00X+013992Y+009807               S0      
317PSU1_REMOTE_P    J1    -40   D0440PA00X+013992Y+008807               S0      
317GND              J1    -44   D0440PA00X+013992Y+012807               S0      
317GND              J1    -43   D0440PA00X+013992Y+011807               S0      
317GND              J1    -42   D0440PA00X+013992Y+010807               S0      
317GND              J1    -46   D0440PA00X+013992Y+014807               S0      
317GND              J1    -45   D0440PA00X+013992Y+013807               S0      
317GND              J1    -49   D0440PA00X+013992Y+017807               S0      
317GND              J1    -48   D0440PA00X+013992Y+016807               S0      
317GND              J1    -47   D0440PA00X+013992Y+015807               S0      
317GND              J1    -51   D0440PA00X+013992Y+019807               S0      
317GND              J1    -50   D0440PA00X+013992Y+018807               S0      
317P12V             J1    -54   D0440PA00X+013992Y+022807               S0      
317P12V             J1    -53   D0440PA00X+013992Y+021807               S0      
317GND              J1    -52   D0440PA00X+013992Y+020807               S0      
317P12V             J1    -56   D0440PA00X+013992Y+024807               S0      
317P12V             J1    -55   D0440PA00X+013992Y+023807               S0      
317P12V             J1    -58   D0440PA00X+013992Y+026807               S0      
317P12V             J1    -57   D0440PA00X+013992Y+025807               S0      
317P12V             J1    -61   D0440PA00X+013992Y+029807               S0      
317P12V             J1    -60   D0440PA00X+013992Y+028807               S0      
317P12V             J1    -59   D0440PA00X+013992Y+027807               S0      
317P12V             J1    -63   D0440PA00X+013992Y+031807               S0      
317P12V             J1    -62   D0440PA00X+013992Y+030807               S0      
317P12V             J1    -64   D0440PA00X+013992Y+032807               S0      
317I2C_PSU1_SDA     J2    -33   D0440PA00X+013992Y+036610               S0      
317PSU2_RETURN      J2    -36   D0440PA00X+013992Y+039610               S0      
317I2C_PSU1_SCL     J2    -35   D0440PA00X+013992Y+038610               S0      
317N/C              J2    -34   D0440PA00X+013992Y+037610               S0      
317PSU2_AD0         J2    -38   D0440PA00X+013992Y+041610               S0      
317PSU2_DC_OK       J2    -37   D0440PA00X+013992Y+040610               S0      
317PSU2_REMOTE_P    J2    -40   D0440PA00X+013992Y+043610               S0      
317P12V_STBY        J2    -39   D0440PA00X+013992Y+042610               S0      
317GND              J2    -43   D0440PA00X+013992Y+046610               S0      
317GND              J2    -42   D0440PA00X+013992Y+045610               S0      
317GND              J2    -41   D0440PA00X+013992Y+044610               S0      
317GND              J2    -45   D0440PA00X+013992Y+048610               S0      
317GND              J2    -44   D0440PA00X+013992Y+047610               S0      
317GND              J2    -48   D0440PA00X+013992Y+051610               S0      
317GND              J2    -47   D0440PA00X+013992Y+050610               S0      
317GND              J2    -46   D0440PA00X+013992Y+049610               S0      
317GND              J2    -50   D0440PA00X+013992Y+053610               S0      
317GND              J2    -49   D0440PA00X+013992Y+052610               S0      
317P12V             J2    -53   D0440PA00X+013992Y+056610               S0      
317GND              J2    -52   D0440PA00X+013992Y+055610               S0      
317GND              J2    -51   D0440PA00X+013992Y+054610               S0      
317P12V             J2    -55   D0440PA00X+013992Y+058610               S0      
317P12V             J2    -54   D0440PA00X+013992Y+057610               S0      
317P12V             J2    -57   D0440PA00X+013992Y+060610               S0      
317P12V             J2    -56   D0440PA00X+013992Y+059610               S0      
317P12V             J2    -60   D0440PA00X+013992Y+063610               S0      
317P12V             J2    -59   D0440PA00X+013992Y+062610               S0      
317P12V             J2    -58   D0440PA00X+013992Y+061610               S0      
317P12V             J2    -62   D0440PA00X+013992Y+065610               S0      
317P12V             J2    -61   D0440PA00X+013992Y+064610               S0      
317P12V             J2    -64   D0440PA00X+013992Y+067610               S0      
317P12V             J2    -63   D0440PA00X+013992Y+066610               S0      
317I2C_PSU2_SCL     J3    -35   D0440PA00X+013992Y+073413               S0      
317N/C              J3    -34   D0440PA00X+013992Y+072413               S0      
317I2C_PSU2_SDA     J3    -33   D0440PA00X+013992Y+071413               S0      
317PSU3_DC_OK       J3    -37   D0440PA00X+013992Y+075413               S0      
317PSU3_RETURN      J3    -36   D0440PA00X+013992Y+074413               S0      
317P12V_STBY        J3    -39   D0440PA00X+013992Y+077413               S0      
317PSU3_AD0         J3    -38   D0440PA00X+013992Y+076413               S0      
317GND              J3    -42   D0440PA00X+013992Y+080413               S0      
317GND              J3    -41   D0440PA00X+013992Y+079413               S0      
317PSU3_REMOTE_P    J3    -40   D0440PA00X+013992Y+078413               S0      
317GND              J3    -44   D0440PA00X+013992Y+082413               S0      
317GND              J3    -43   D0440PA00X+013992Y+081413               S0      
317GND              J3    -47   D0440PA00X+013992Y+085413               S0      
317GND              J3    -46   D0440PA00X+013992Y+084413               S0      
317GND              J3    -45   D0440PA00X+013992Y+083413               S0      
317GND              J3    -49   D0440PA00X+013992Y+087413               S0      
317GND              J3    -48   D0440PA00X+013992Y+086413               S0      
317GND              J3    -52   D0440PA00X+013992Y+090413               S0      
317GND              J3    -51   D0440PA00X+013992Y+089413               S0      
317GND              J3    -50   D0440PA00X+013992Y+088413               S0      
317P12V             J3    -54   D0440PA00X+013992Y+092413               S0      
317P12V             J3    -53   D0440PA00X+013992Y+091413               S0      
317P12V             J3    -56   D0440PA00X+013992Y+094413               S0      
317P12V             J3    -55   D0440PA00X+013992Y+093413               S0      
317P12V             J3    -59   D0440PA00X+013992Y+097413               S0      
317P12V             J3    -58   D0440PA00X+013992Y+096413               S0      
317P12V             J3    -57   D0440PA00X+013992Y+095413               S0      
317P12V             J3    -61   D0440PA00X+013992Y+099413               S0      
317P12V             J3    -60   D0440PA00X+013992Y+098413               S0      
317P12V             J3    -64   D0440PA00X+013992Y+102413               S0      
317P12V             J3    -63   D0440PA00X+013992Y+101413               S0      
317P12V             J3    -62   D0440PA00X+013992Y+100413               S0      
317N/C              J4    -34   D0440PA00X+013992Y+107217               S0      
317I2C_PSU2_SDA     J4    -33   D0440PA00X+013992Y+106217               S0      
317PSU4_RETURN      J4    -36   D0440PA00X+013992Y+109217               S0      
317I2C_PSU2_SCL     J4    -35   D0440PA00X+013992Y+108217               S0      
317P12V_STBY        J4    -39   D0440PA00X+013992Y+112217               S0      
317PSU4_AD0         J4    -38   D0440PA00X+013992Y+111217               S0      
317PSU4_DC_OK       J4    -37   D0440PA00X+013992Y+110217               S0      
317GND              J4    -41   D0440PA00X+013992Y+114217               S0      
317PSU4_REMOTE_P    J4    -40   D0440PA00X+013992Y+113217               S0      
317GND              J4    -43   D0440PA00X+013992Y+116217               S0      
317GND              J4    -42   D0440PA00X+013992Y+115217               S0      
317GND              J4    -46   D0440PA00X+013992Y+119217               S0      
317GND              J4    -45   D0440PA00X+013992Y+118217               S0      
317GND              J4    -44   D0440PA00X+013992Y+117217               S0      
317GND              J4    -48   D0440PA00X+013992Y+121217               S0      
317GND              J4    -47   D0440PA00X+013992Y+120217               S0      
317GND              J4    -51   D0440PA00X+013992Y+124217               S0      
317GND              J4    -50   D0440PA00X+013992Y+123217               S0      
317GND              J4    -49   D0440PA00X+013992Y+122217               S0      
317P12V             J4    -53   D0440PA00X+013992Y+126217               S0      
317GND              J4    -52   D0440PA00X+013992Y+125217               S0      
317P12V             J4    -55   D0440PA00X+013992Y+128217               S0      
317P12V             J4    -54   D0440PA00X+013992Y+127217               S0      
317P12V             J4    -58   D0440PA00X+013992Y+131217               S0      
317P12V             J4    -57   D0440PA00X+013992Y+130217               S0      
317P12V             J4    -56   D0440PA00X+013992Y+129217               S0      
317P12V             J4    -60   D0440PA00X+013992Y+133217               S0      
317P12V             J4    -59   D0440PA00X+013992Y+132217               S0      
317P12V             J4    -63   D0440PA00X+013992Y+136217               S0      
317P12V             J4    -62   D0440PA00X+013992Y+135217               S0      
317P12V             J4    -61   D0440PA00X+013992Y+134217               S0      
317P12V             J4    -64   D0440PA00X+013992Y+137217               S0      
317I2C_PSU3_SDA     J5    -33   D0440PA00X+013992Y+141020               S0      
317I2C_PSU3_SCL     J5    -35   D0440PA00X+013992Y+143020               S0      
317N/C              J5    -34   D0440PA00X+013992Y+142020               S0      
317PSU5_AD0         J5    -38   D0440PA00X+013992Y+146020               S0      
317PSU5_DC_OK       J5    -37   D0440PA00X+013992Y+145020               S0      
317PSU5_RETURN      J5    -36   D0440PA00X+013992Y+144020               S0      
317PSU5_REMOTE_P    J5    -40   D0440PA00X+013992Y+148020               S0      
317P12V_STBY        J5    -39   D0440PA00X+013992Y+147020               S0      
317GND              J5    -42   D0440PA00X+013992Y+150020               S0      
317GND              J5    -41   D0440PA00X+013992Y+149020               S0      
317GND              J5    -45   D0440PA00X+013992Y+153020               S0      
317GND              J5    -44   D0440PA00X+013992Y+152020               S0      
317GND              J5    -43   D0440PA00X+013992Y+151020               S0      
317GND              J5    -47   D0440PA00X+013992Y+155020               S0      
317GND              J5    -46   D0440PA00X+013992Y+154020               S0      
317GND              J5    -50   D0440PA00X+013992Y+158020               S0      
317GND              J5    -49   D0440PA00X+013992Y+157020               S0      
317GND              J5    -48   D0440PA00X+013992Y+156020               S0      
317GND              J5    -52   D0440PA00X+013992Y+160020               S0      
317GND              J5    -51   D0440PA00X+013992Y+159020               S0      
317P12V             J5    -54   D0440PA00X+013992Y+162020               S0      
317P12V             J5    -53   D0440PA00X+013992Y+161020               S0      
317P12V             J5    -57   D0440PA00X+013992Y+165020               S0      
317P12V             J5    -56   D0440PA00X+013992Y+164020               S0      
317P12V             J5    -55   D0440PA00X+013992Y+163020               S0      
317P12V             J5    -59   D0440PA00X+013992Y+167020               S0      
317P12V             J5    -58   D0440PA00X+013992Y+166020               S0      
317P12V             J5    -62   D0440PA00X+013992Y+170020               S0      
317P12V             J5    -61   D0440PA00X+013992Y+169020               S0      
317P12V             J5    -60   D0440PA00X+013992Y+168020               S0      
317P12V             J5    -64   D0440PA00X+013992Y+172020               S0      
317P12V             J5    -63   D0440PA00X+013992Y+171020               S0      
317T11_BLAD1_TXD    VIA   -     D0100PA00X+014488Y+173886               S1      
317N/C              J6    -34   D0440PA00X+013992Y+176823               S0      
317I2C_PSU3_SDA     J6    -33   D0440PA00X+013992Y+175823               S0      
317PSU6_DC_OK       J6    -37   D0440PA00X+013992Y+179823               S0      
317PSU6_RETURN      J6    -36   D0440PA00X+013992Y+178823               S0      
317I2C_PSU3_SCL     J6    -35   D0440PA00X+013992Y+177823               S0      
317P12V_STBY        J6    -39   D0440PA00X+013992Y+181823               S0      
317PSU6_AD0         J6    -38   D0440PA00X+013992Y+180823               S0      
317GND              J6    -41   D0440PA00X+013992Y+183823               S0      
317PSU6_REMOTE_P    J6    -40   D0440PA00X+013992Y+182823               S0      
317GND              J6    -44   D0440PA00X+013992Y+186823               S0      
317GND              J6    -43   D0440PA00X+013992Y+185823               S0      
317GND              J6    -42   D0440PA00X+013992Y+184823               S0      
317GND              J6    -46   D0440PA00X+013992Y+188823               S0      
317GND              J6    -45   D0440PA00X+013992Y+187823               S0      
317GND              J6    -49   D0440PA00X+013992Y+191823               S0      
317GND              J6    -48   D0440PA00X+013992Y+190823               S0      
317GND              J6    -47   D0440PA00X+013992Y+189823               S0      
317GND              J6    -51   D0440PA00X+013992Y+193823               S0      
317GND              J6    -50   D0440PA00X+013992Y+192823               S0      
317P12V             J6    -53   D0440PA00X+013992Y+195823               S0      
317GND              J6    -52   D0440PA00X+013992Y+194823               S0      
317P12V             J6    -56   D0440PA00X+013992Y+198823               S0      
317P12V             J6    -55   D0440PA00X+013992Y+197823               S0      
317P12V             J6    -54   D0440PA00X+013992Y+196823               S0      
317P12V             J6    -58   D0440PA00X+013992Y+200823               S0      
317P12V             J6    -57   D0440PA00X+013992Y+199823               S0      
317P12V             J6    -61   D0440PA00X+013992Y+203823               S0      
317P12V             J6    -60   D0440PA00X+013992Y+202823               S0      
317P12V             J6    -59   D0440PA00X+013992Y+201823               S0      
317P12V             J6    -63   D0440PA00X+013992Y+205823               S0      
317P12V             J6    -62   D0440PA00X+013992Y+204823               S0      
317P12V             J6    -64   D0440PA00X+013992Y+206823               S0      
317N/C              J7    -H2   D0990UA00X+016339Y+002721               S0      
327GND              R9    -2          A01X+015968Y+005674X0180Y0200R180 S2      
327PSU1_RETURN      R9    -1          A01X+015653Y+005674X0180Y0200R180 S2      
317GND              VIA   -     D0100PA00X+016238Y+005674               S3      
317PSU1_RETURN      VIA   -     D0100PA00X+015756Y+005143               S1      
327GND              R12   -2          A01X+015846Y+006813X0180Y0200R180 S2      
327PSU1_AD0         R12   -1          A01X+015531Y+006813X0180Y0200R180 S2      
327P12V_STBY        R40   -2          A01X+015520Y+007250X0180Y0200     S2      
327GND              R40   -1          A01X+015835Y+007250X0180Y0200     S2      
317GND              VIA   -     D0100PA00X+016174Y+007250               S3      
317GND              VIA   -     D0100PA00X+016259Y+006813               S3      
327P12V             R1    -2          A01X+015856Y+008811X0180Y0200R180 S2      
327PSU1_REMOTE_P    R1    -1          A01X+015541Y+008811X0180Y0200R180 S2      
327NNAME10042       R86   -2          A01X+015537Y+009128X0180Y0200R270 S2      
327PSU1_REMOTE_P    R86   -1          A01X+015537Y+008813X0180Y0200R270 S2      
327NNAME10043       R110  -2          A01X+015537Y+008502X0180Y0200R090 S2      
327PSU1_REMOTE_P    R110  -1          A01X+015537Y+008817X0180Y0200R090 S2      
317P12V             VIA   -     D0100PA00X+016134Y+008811               S3      
317NNAME10042       VIA   -     D0100PA00X+015942Y+009128               S3      
317NNAME10043       VIA   -     D0100PA00X+015890Y+008502               S3      
317GND              VIA   -     D0200PA00X+016650Y+012611               S3      
317GND              VIA   -     D0200PA00X+016650Y+011863               S3      
317GND              VIA   -     D0200PA00X+016650Y+011141               S3      
317GND              VIA   -     D0200PA00X+016633Y+014062               S3      
317GND              VIA   -     D0200PA00X+016650Y+013271               S3      
317GND              VIA   -     D0200PA00X+016633Y+014807               S3      
317GND              VIA   -     D0200PA00X+016633Y+015610               S3      
317GND              VIA   -     D0200PA00X+016633Y+016362               S3      
317N/C              J8    -H2   D0990UA00X+016339Y+020221               S0      
317P12V             VIA   -     D0200PA00X+016598Y+026578               S3      
317P12V             VIA   -     D0200PA00X+016598Y+029614               S3      
317P12V             VIA   -     D0200PA00X+016598Y+028680               S3      
317P12V             VIA   -     D0200PA00X+016598Y+027630               S3      
317P12V             VIA   -     D0200PA00X+016598Y+031231               S3      
317P12V             VIA   -     D0200PA00X+016598Y+030387               S3      
317N/C              J9    -H2   D0990UA00X+016339Y+037721               S0      
327P12V_STBY        R4    -2          A01X+015632Y+041820X0180Y0200R270 S2      
327PSU2_AD0         R4    -1          A01X+015632Y+041505X0180Y0200R270 S2      
327GND              R11   -2          A01X+015849Y+040758X0180Y0200R180 S2      
327PSU2_RETURN      R11   -1          A01X+015534Y+040758X0180Y0200R180 S2      
327GND              R8    -2          A01X+016126Y+041820X0180Y0200R270 S2      
327PSU2_AD0         R8    -1          A01X+016126Y+041505X0180Y0200R270 S2      
317GND              VIA   -     D0100PA00X+016138Y+040758               S3      
317PSU2_RETURN      VIA   -     D0100PA00X+015687Y+040121               S1      
327P12V             R3    -2          A01X+015850Y+043612X0180Y0200R180 S2      
327PSU2_REMOTE_P    R3    -1          A01X+015535Y+043612X0180Y0200R180 S2      
327NNAME10044       R90   -2          A01X+015535Y+043927X0180Y0200R270 S2      
327PSU2_REMOTE_P    R90   -1          A01X+015535Y+043612X0180Y0200R270 S2      
327NNAME10045       R114  -2          A01X+015535Y+043297X0180Y0200R090 S2      
327PSU2_REMOTE_P    R114  -1          A01X+015535Y+043612X0180Y0200R090 S2      
317P12V             VIA   -     D0100PA00X+016152Y+043612               S3      
317GND              VIA   -     D0100PA00X+016126Y+042087               S3      
317NNAME10044       VIA   -     D0100PA00X+015902Y+043927               S3      
317NNAME10045       VIA   -     D0100PA00X+015881Y+043297               S3      
317GND              VIA   -     D0200PA00X+015643Y+046171               S3      
317GND              VIA   -     D0200PA00X+015643Y+048301               S3      
317GND              VIA   -     D0200PA00X+015626Y+049093               S3      
317GND              VIA   -     D0200PA00X+015643Y+046893               S3      
317GND              VIA   -     D0200PA00X+015643Y+047642               S3      
317GND              VIA   -     D0200PA00X+015626Y+051393               S3      
317GND              VIA   -     D0200PA00X+015626Y+049837               S3      
317GND              VIA   -     D0200PA00X+015626Y+050641               S3      
317N/C              J10   -H2   D0990UA00X+016339Y+055221               S0      
317P12V             VIA   -     D0200PA00X+015727Y+060477               S3      
317P12V             VIA   -     D0200PA00X+015727Y+063342               S3      
317P12V             VIA   -     D0200PA00X+015727Y+061357               S3      
317P12V             VIA   -     D0200PA00X+015727Y+062408               S3      
317P12V             VIA   -     D0200PA00X+015727Y+064114               S3      
317P12V             VIA   -     D0200PA00X+015727Y+064958               S3      
317N/C              J11   -H2   D0990UA00X+016339Y+072721               S0      
327GND              R10   -2          A01X+015895Y+075676X0180Y0200R180 S2      
327PSU3_RETURN      R10   -1          A01X+015580Y+075676X0180Y0200R180 S2      
317PSU3_RETURN      VIA   -     D0100PA00X+015661Y+075106               S1      
317GND              VIA   -     D0100PA00X+016183Y+075676               S3      
327GND              R13   -2          A01X+015867Y+076423X0180Y0200R180 S2      
327PSU3_AD0         R13   -1          A01X+015552Y+076423X0180Y0200R180 S2      
327P12V_STBY        R42   -2          A01X+015511Y+077667X0180Y0200     S2      
327GND              R42   -1          A01X+015826Y+077667X0180Y0200     S2      
327NNAME10046       R118  -2          A01X+015536Y+078098X0180Y0200R090 S2      
317GND              VIA   -     D0100PA00X+016113Y+077488               S3      
317GND              VIA   -     D0100PA00X+016164Y+076423               S3      
317NNAME10046       VIA   -     D0100PA00X+015896Y+078098               S3      
327P12V             R2    -2          A01X+015852Y+078414X0180Y0200R180 S2      
327PSU3_REMOTE_P    R2    -1          A01X+015537Y+078414X0180Y0200R180 S2      
327NNAME10037       R94   -2          A01X+015536Y+078728X0180Y0200R270 S2      
327PSU3_REMOTE_P    R94   -1          A01X+015536Y+078413X0180Y0200R270 S2      
327PSU3_REMOTE_P    R118  -1          A01X+015536Y+078413X0180Y0200R090 S2      
317P12V             VIA   -     D0100PA00X+016148Y+078414               S3      
317NNAME10037       VIA   -     D0100PA00X+015905Y+078728               S3      
317GND              VIA   -     D0200PA00X+015544Y+082273               S3      
317GND              VIA   -     D0200PA00X+016287Y+082273               S3      
317GND              VIA   -     D0200PA00X+016287Y+083021               S3      
317GND              VIA   -     D0200PA00X+015544Y+083021               S3      
317GND              VIA   -     D0200PA00X+017152Y+084472               S3      
317GND              VIA   -     D0200PA00X+017152Y+085217               S3      
317GND              VIA   -     D0200PA00X+016287Y+083680               S3      
317GND              VIA   -     D0200PA00X+015544Y+083680               S3      
317GND              VIA   -     D0200PA00X+016270Y+084472               S3      
317GND              VIA   -     D0200PA00X+015527Y+084472               S3      
317GND              VIA   -     D0200PA00X+016270Y+085217               S3      
317GND              VIA   -     D0200PA00X+015527Y+085217               S3      
317GND              VIA   -     D0200PA00X+017152Y+086020               S3      
317GND              VIA   -     D0200PA00X+017152Y+086772               S3      
317GND              VIA   -     D0200PA00X+016270Y+086020               S3      
317GND              VIA   -     D0200PA00X+015527Y+086020               S3      
317GND              VIA   -     D0200PA00X+016270Y+086772               S3      
317GND              VIA   -     D0200PA00X+015527Y+086772               S3      
317N/C              J12   -H2   D0990UA00X+016339Y+090221               S0      
317P12V             VIA   -     D0200PA00X+016670Y+097292               S3      
317P12V             VIA   -     D0200PA00X+016670Y+098344               S3      
317P12V             VIA   -     D0200PA00X+016670Y+099394               S3      
317P12V             VIA   -     D0200PA00X+016642Y+101130               S3      
317P12V             VIA   -     D0200PA00X+016642Y+100357               S3      
317P12V             VIA   -     D0200PA00X+016642Y+101974               S3      
317N/C              J13   -H2   D0990UA00X+016339Y+107721               S0      
327P12V_STBY        R16   -2          A01X+015612Y+111613X0180Y0200R270 S2      
327PSU4_AD0         R16   -1          A01X+015612Y+111298X0180Y0200R270 S2      
327GND              R25   -2          A01X+015928Y+110685X0180Y0200R180 S2      
327PSU4_RETURN      R25   -1          A01X+015613Y+110685X0180Y0200R180 S2      
327GND              R21   -2          A01X+016087Y+111614X0180Y0200R270 S2      
327PSU4_AD0         R21   -1          A01X+016087Y+111299X0180Y0200R270 S2      
317GND              VIA   -     D0100PA00X+016454Y+111614               S3      
317GND              VIA   -     D0100PA00X+016214Y+110685               S3      
317PSU4_RETURN      VIA   -     D0100PA00X+015685Y+110103               S1      
327P12V             R15   -2          A01X+015850Y+113218X0180Y0200R180 S2      
327PSU4_REMOTE_P    R15   -1          A01X+015535Y+113218X0180Y0200R180 S2      
327NNAME10029       R106  -2          A01X+015526Y+113534X0180Y0200R270 S2      
327PSU4_REMOTE_P    R106  -1          A01X+015526Y+113219X0180Y0200R270 S2      
327NNAME10047       R122  -2          A01X+015526Y+112905X0180Y0200R090 S2      
327PSU4_REMOTE_P    R122  -1          A01X+015526Y+113220X0180Y0200R090 S2      
317NNAME10029       VIA   -     D0100PA00X+015938Y+113615               S3      
317NNAME10047       VIA   -     D0100PA00X+015846Y+112905               S3      
317GND              VIA   -     D0200PA00X+016938Y+117626               S3      
317GND              VIA   -     D0200PA00X+016938Y+119034               S3      
317GND              VIA   -     D0200PA00X+016938Y+118374               S3      
317GND              VIA   -     D0200PA00X+015312Y+117626               S3      
317GND              VIA   -     D0200PA00X+016055Y+117626               S3      
317GND              VIA   -     D0200PA00X+016055Y+118374               S3      
317GND              VIA   -     D0200PA00X+016055Y+119034               S3      
317GND              VIA   -     D0200PA00X+015312Y+119034               S3      
317GND              VIA   -     D0200PA00X+015312Y+118374               S3      
317GND              VIA   -     D0200PA00X+016055Y+116904               S3      
317GND              VIA   -     D0200PA00X+015312Y+116904               S3      
317GND              VIA   -     D0200PA00X+016920Y+119825               S3      
317GND              VIA   -     D0200PA00X+016038Y+119825               S3      
317GND              VIA   -     D0200PA00X+015295Y+119825               S3      
317N/C              J14   -H2   D0990UA00X+016339Y+125221               S0      
317P12V             VIA   -     D0200PA00X+015575Y+130773               S3      
317P12V             VIA   -     D0200PA00X+015575Y+132875               S3      
317P12V             VIA   -     D0200PA00X+015575Y+131825               S3      
317P12V             VIA   -     D0200PA00X+015575Y+135426               S3      
317P12V             VIA   -     D0200PA00X+015575Y+133809               S3      
317P12V             VIA   -     D0200PA00X+015575Y+134582               S3      
317T9_BLAD2_RXD     VIA   -     D0100PA00X+015862Y+139945               S1      
317T9_BLAD2_TXD     VIA   -     D0100PA00X+016404Y+140023               S1      
317T9_BLAD3_TXD     VIA   -     D0100PA00X+017035Y+140132               S1      
317N/C              J15   -H2   D0990UA00X+016339Y+142721               S0      
327GND              R24   -2          A01X+016025Y+145708X0180Y0200R180 S2      
327PSU5_RETURN      R24   -1          A01X+015710Y+145708X0180Y0200R180 S2      
317PSU5_RETURN      VIA   -     D0100PA00X+015919Y+145111               S1      
317GND              VIA   -     D0100PA00X+016310Y+145708               S3      
327P12V             R14   -2          A01X+015898Y+148027X0180Y0200R180 S2      
327PSU5_REMOTE_P    R14   -1          A01X+015583Y+148027X0180Y0200R180 S2      
327GND              R27   -2          A01X+015951Y+146265X0180Y0200R180 S2      
327PSU5_AD0         R27   -1          A01X+015636Y+146265X0180Y0200R180 S2      
327P12V_STBY        R44   -2          A01X+015565Y+147302X0180Y0200     S2      
327GND              R44   -1          A01X+015880Y+147302X0180Y0200     S2      
327PSU5_REMOTE_P    R102  -1          A01X+015583Y+148027X0180Y0200R270 S2      
327NNAME10048       R126  -2          A01X+015582Y+147712X0180Y0200R090 S2      
327PSU5_REMOTE_P    R126  -1          A01X+015582Y+148027X0180Y0200R090 S2      
317GND              VIA   -     D0100PA00X+016252Y+146265               S3      
317GND              VIA   -     D0100PA00X+016224Y+147138               S3      
317NNAME10048       VIA   -     D0100PA00X+015922Y+147712               S3      
327NNAME10049       R102  -2          A01X+015583Y+148342X0180Y0200R270 S2      
317GND              VIA   -     D0200PA00X+015411Y+149922               S3      
317GND              VIA   -     D0200PA00X+016154Y+149922               S3      
317GND              VIA   -     D0200PA00X+016154Y+150644               S3      
317GND              VIA   -     D0200PA00X+017036Y+150644               S3      
317GND              VIA   -     D0200PA00X+015411Y+150644               S3      
317NNAME10049       VIA   -     D0100PA00X+015953Y+148343               S3      
317GND              VIA   -     D0200PA00X+015394Y+152844               S3      
317GND              VIA   -     D0200PA00X+015411Y+151392               S3      
317GND              VIA   -     D0200PA00X+015411Y+152052               S3      
317GND              VIA   -     D0200PA00X+017036Y+151392               S3      
317GND              VIA   -     D0200PA00X+017036Y+152052               S3      
317GND              VIA   -     D0200PA00X+016154Y+152052               S3      
317GND              VIA   -     D0200PA00X+016154Y+151392               S3      
317GND              VIA   -     D0200PA00X+016137Y+152844               S3      
317GND              VIA   -     D0200PA00X+017019Y+152844               S3      
317GND              VIA   -     D0200PA00X+015394Y+153588               S3      
317GND              VIA   -     D0200PA00X+015394Y+154392               S3      
317GND              VIA   -     D0200PA00X+015394Y+155144               S3      
317GND              VIA   -     D0200PA00X+017019Y+153588               S3      
317GND              VIA   -     D0200PA00X+017019Y+154392               S3      
317GND              VIA   -     D0200PA00X+016137Y+153588               S3      
317GND              VIA   -     D0200PA00X+016137Y+154392               S3      
317GND              VIA   -     D0200PA00X+016137Y+155144               S3      
317GND              VIA   -     D0200PA00X+017019Y+155144               S3      
317N/C              J16   -H2   D0990UA00X+016339Y+160221               S0      
317P12V             VIA   -     D0200PA00X+015849Y+166776               S3      
317P12V             VIA   -     D0200PA00X+015849Y+165725               S3      
317P12V             VIA   -     D0200PA00X+015849Y+169533               S3      
317P12V             VIA   -     D0200PA00X+015849Y+168761               S3      
317P12V             VIA   -     D0200PA00X+015849Y+167827               S3      
317P12V             VIA   -     D0200PA00X+015849Y+170377               S3      
317T11_BLAD1_RXD    VIA   -     D0100PA00X+015031Y+173701               S1      
317T11_BLAD3_TXD    VIA   -     D0100PA00X+016815Y+173921               S1      
317T11_BLAD2_RXD    VIA   -     D0100PA00X+015618Y+173524               S1      
317T11_BLAD4_RXD    VIA   -     D0100PA00X+016578Y+173290               S1      
317T11_BLAD3_RXD    VIA   -     D0100PA00X+016326Y+173762               S1      
317N/C              J17   -H2   D0990UA00X+016339Y+177721               S0      
327GND              R26   -2          A01X+015884Y+180774X0180Y0200R180 S2      
327PSU6_RETURN      R26   -1          A01X+015569Y+180774X0180Y0200R180 S2      
327GND              R23   -2          A01X+015856Y+181563X0180Y0200R180 S2      
327PSU6_AD0         R23   -1          A01X+015541Y+181563X0180Y0200R180 S2      
317GND              VIA   -     D0100PA00X+016325Y+181563               S3      
317GND              VIA   -     D0100PA00X+016214Y+180774               S3      
317PSU6_RETURN      VIA   -     D0100PA00X+015645Y+180082               S1      
327P12V             R17   -2          A01X+015881Y+182823X0180Y0200R180 S2      
327PSU6_REMOTE_P    R17   -1          A01X+015566Y+182823X0180Y0200R180 S2      
327P12V_STBY        R18   -2          A01X+015541Y+182036X0180Y0200     S2      
327PSU6_AD0         R18   -1          A01X+015856Y+182036X0180Y0200     S2      
327NNAME10027       R98   -2          A01X+015557Y+183138X0180Y0200R270 S2      
327PSU6_REMOTE_P    R98   -1          A01X+015557Y+182823X0180Y0200R270 S2      
327NNAME10050       R130  -2          A01X+015556Y+182509X0180Y0200R090 S2      
327PSU6_REMOTE_P    R130  -1          A01X+015556Y+182824X0180Y0200R090 S2      
317P12V             VIA   -     D0100PA00X+016184Y+182823               S3      
317NNAME10027       VIA   -     D0100PA00X+015982Y+183138               S3      
317NNAME10050       VIA   -     D0100PA00X+015908Y+182509               S3      
317GND              VIA   -     D0200PA00X+015209Y+186600               S3      
317GND              VIA   -     D0200PA00X+015952Y+186600               S3      
317GND              VIA   -     D0200PA00X+015209Y+188071               S3      
317GND              VIA   -     D0200PA00X+015209Y+188730               S3      
317GND              VIA   -     D0200PA00X+016834Y+188071               S3      
317GND              VIA   -     D0200PA00X+016834Y+188730               S3      
317GND              VIA   -     D0200PA00X+015952Y+188730               S3      
317GND              VIA   -     D0200PA00X+015952Y+188071               S3      
317GND              VIA   -     D0200PA00X+015952Y+187322               S3      
317GND              VIA   -     D0200PA00X+016834Y+187322               S3      
317GND              VIA   -     D0200PA00X+015209Y+187322               S3      
317GND              VIA   -     D0200PA00X+015192Y+190266               S3      
317GND              VIA   -     D0200PA00X+015192Y+191070               S3      
317GND              VIA   -     D0200PA00X+016817Y+190266               S3      
317GND              VIA   -     D0200PA00X+016817Y+191070               S3      
317GND              VIA   -     D0200PA00X+015935Y+190266               S3      
317GND              VIA   -     D0200PA00X+015935Y+191070               S3      
317GND              VIA   -     D0200PA00X+015192Y+189522               S3      
317GND              VIA   -     D0200PA00X+015935Y+189522               S3      
317GND              VIA   -     D0200PA00X+016817Y+189522               S3      
317GND              VIA   -     D0200PA00X+015192Y+191822               S3      
317GND              VIA   -     D0200PA00X+015935Y+191822               S3      
317GND              VIA   -     D0200PA00X+016817Y+191822               S3      
317N/C              J18   -H2   D0990UA00X+016339Y+195221               S0      
317GND              VIA   -     D0100PA00X+015999Y+208361               S3      
317GND              VIA   -     D0100PA00X+017522Y+000300               S3      
317GND              J7    -P1   D0300PA00X+017339Y+003252               S0      
317GND              J7    -P32  D0300PA00X+017339Y+002189               S0      
317GND              J7    -P2   D0300PA00X+018339Y+003252               S0      
317GND              J7    -P31  D0300PA00X+018339Y+002189               S0      
317GND              J7    -P3   D0300PA00X+019339Y+003252               S0      
317GND              J7    -P30  D0300PA00X+019339Y+002189               S0      
317GND              CE1   -2    D0360PA00X+018976Y+007311               S0      
317GND              VIA   -     D0200PA00X+017393Y+012611               S3      
317GND              VIA   -     D0200PA00X+017393Y+011863               S3      
317GND              VIA   -     D0200PA00X+017393Y+011141               S3      
317GND              CE2   -2    D0360PA00X+019029Y+015205               S0      
317GND              VIA   -     D0200PA00X+017376Y+014062               S3      
317GND              VIA   -     D0200PA00X+017393Y+013271               S3      
317GND              VIA   -     D0200PA00X+017376Y+014807               S3      
317GND              VIA   -     D0200PA00X+017376Y+015610               S3      
317GND              VIA   -     D0200PA00X+017376Y+016362               S3      
317GND              J8    -P32  D0300PA00X+017339Y+019689               S0      
317GND              J8    -P31  D0300PA00X+018339Y+019689               S0      
317GND              J8    -P30  D0300PA00X+019339Y+019689               S0      
317GND              J8    -P1   D0300PA00X+017339Y+020752               S0      
317GND              J8    -P2   D0300PA00X+018339Y+020752               S0      
317GND              J8    -P3   D0300PA00X+019339Y+020752               S0      
317GND              CE3   -2    D0360PA00X+019036Y+024757               S0      
317GND              VIA   -     D0200PA00X+017503Y+026159               S3      
317GND              VIA   -     D0200PA00X+017503Y+026881               S3      
317GND              VIA   -     D0200PA00X+017503Y+028289               S3      
317GND              VIA   -     D0200PA00X+017486Y+029081               S3      
317GND              VIA   -     D0200PA00X+017486Y+029825               S3      
317GND              VIA   -     D0200PA00X+017503Y+027630               S3      
317GND              VIA   -     D0200PA00X+017486Y+031381               S3      
317GND              VIA   -     D0200PA00X+017486Y+030629               S3      
317GND              CE4   -2    D0360PA00X+019082Y+033179               S0      
317GND              J9    -P32  D0300PA00X+017339Y+037189               S0      
317GND              J9    -P31  D0300PA00X+018339Y+037189               S0      
317GND              J9    -P30  D0300PA00X+019339Y+037189               S0      
317GND              J9    -P1   D0300PA00X+017339Y+038252               S0      
317GND              J9    -P2   D0300PA00X+018339Y+038252               S0      
317GND              J9    -P3   D0300PA00X+019339Y+038252               S0      
317GND              CE5   -2    D0360PA00X+018976Y+042173               S0      
317GND              CE6   -2    D0360PA00X+019055Y+050652               S0      
317GND              J10   -P1   D0300PA00X+017339Y+055752               S0      
317GND              J10   -P32  D0300PA00X+017339Y+054689               S0      
317GND              J10   -P2   D0300PA00X+018339Y+055752               S0      
317GND              J10   -P31  D0300PA00X+018339Y+054689               S0      
317GND              J10   -P3   D0300PA00X+019339Y+055752               S0      
317GND              J10   -P30  D0300PA00X+019339Y+054689               S0      
317GND              CE8   -2    D0360PA00X+019289Y+059813               S0      
317GND              CE9   -2    D0360PA00X+019082Y+068165               S0      
317GND              J11   -P1   D0300PA00X+017339Y+073252               S0      
317GND              J11   -P32  D0300PA00X+017339Y+072189               S0      
317GND              J11   -P2   D0300PA00X+018339Y+073252               S0      
317GND              J11   -P31  D0300PA00X+018339Y+072189               S0      
317GND              J11   -P3   D0300PA00X+019339Y+073252               S0      
317GND              J11   -P30  D0300PA00X+019339Y+072189               S0      
317GND              CE10  -2    D0360PA00X+019185Y+077453               S0      
317GND              VIA   -     D0200PA00X+017919Y+082273               S3      
317GND              VIA   -     D0200PA00X+017919Y+083021               S3      
317GND              VIA   -     D0200PA00X+017170Y+082273               S3      
317GND              VIA   -     D0200PA00X+017170Y+083021               S3      
317GND              VIA   -     D0200PA00X+017919Y+083680               S3      
317GND              VIA   -     D0200PA00X+017170Y+083680               S3      
317GND              VIA   -     D0200PA00X+017902Y+084472               S3      
317GND              VIA   -     D0200PA00X+017902Y+085217               S3      
317GND              CE11  -2    D0360PA00X+019161Y+085624               S0      
317GND              VIA   -     D0200PA00X+017902Y+086020               S3      
317GND              VIA   -     D0200PA00X+017902Y+086772               S3      
317GND              J12   -P32  D0300PA00X+017339Y+089689               S0      
317GND              J12   -P31  D0300PA00X+018339Y+089689               S0      
317GND              J12   -P30  D0300PA00X+019339Y+089689               S0      
317GND              J12   -P1   D0300PA00X+017339Y+090752               S0      
317GND              J12   -P2   D0300PA00X+018339Y+090752               S0      
317GND              J12   -P3   D0300PA00X+019339Y+090752               S0      
317GND              CE12  -2    D0360PA00X+019631Y+094720               S0      
327P12V             R88   -2          A01X+018437Y+093798X0180Y0200R180 S2      
327NNAME10042       R88   -1          A01X+018122Y+093798X0180Y0200R180 S2      
327GND              R89   -2          A01X+018428Y+094358X0180Y0200R180 S2      
327NNAME10032       R89   -1          A01X+018113Y+094358X0180Y0200R180 S2      
317GND              VIA   -     D0100PA00X+018428Y+094833               S3      
317NNAME10032       VIA   -     D0100PA00X+017599Y+094454               S1      
317NNAME10042       VIA   -     D0100PA00X+017601Y+093683               S1      
327GND              R91   -2          A01X+018420Y+096267X0180Y0200R180 S2      
327NNAME10033       R91   -1          A01X+018105Y+096267X0180Y0200R180 S2      
327P12V             R92   -2          A01X+018429Y+095707X0180Y0200R180 S2      
327NNAME10044       R92   -1          A01X+018114Y+095707X0180Y0200R180 S2      
327P12V             R96   -2          A01X+018454Y+097355X0180Y0200R180 S2      
327NNAME10037       R96   -1          A01X+018139Y+097355X0180Y0200R180 S2      
317GND              VIA   -     D0100PA00X+018420Y+096737               S3      
317NNAME10033       VIA   -     D0100PA00X+017536Y+096349               S1      
317NNAME10044       VIA   -     D0100PA00X+017556Y+095596               S1      
317NNAME10037       VIA   -     D0100PA00X+017514Y+097249               S1      
327P12V             R100  -2          A01X+018440Y+099096X0180Y0200R180 S2      
327NNAME10027       R100  -1          A01X+018125Y+099096X0180Y0200R180 S2      
327GND              R95   -2          A01X+018463Y+097915X0180Y0200R180 S2      
327NNAME10035       R95   -1          A01X+018148Y+097915X0180Y0200R180 S2      
327GND              R99   -2          A01X+018435Y+099656X0180Y0200R180 S2      
327NNAME10028       R99   -1          A01X+018120Y+099656X0180Y0200R180 S2      
317GND              VIA   -     D0100PA00X+018463Y+098342               S3      
317NNAME10035       VIA   -     D0100PA00X+017502Y+098028               S1      
317NNAME10027       VIA   -     D0100PA00X+017574Y+098996               S1      
317NNAME10028       VIA   -     D0100PA00X+017545Y+099766               S1      
327GND              R107  -2          A01X+018412Y+101531X0180Y0200R180 S2      
327NNAME10030       R107  -1          A01X+018097Y+101531X0180Y0200R180 S2      
327P12V             R108  -2          A01X+018412Y+100971X0180Y0200R180 S2      
327NNAME10029       R108  -1          A01X+018097Y+100971X0180Y0200R180 S2      
317GND              VIA   -     D0100PA00X+018435Y+100156               S3      
317GND              VIA   -     D0100PA00X+018412Y+101928               S3      
317GND              VIA   -     D0100PA00X+018839Y+102081               S3      
317NNAME10029       VIA   -     D0100PA00X+017570Y+100873               S1      
317NNAME10030       VIA   -     D0100PA00X+017547Y+101630               S1      
317GND              CE7   -2    D0360PA00X+019552Y+103254               S0      
327GND              R103  -2          A01X+018233Y+102502X0180Y0200R180 S2      
327NNAME10039       R103  -1          A01X+017918Y+102502X0180Y0200R180 S2      
327P12V             R104  -2          A01X+018233Y+103062X0180Y0200R180 S2      
327NNAME10049       R104  -1          A01X+017918Y+103062X0180Y0200R180 S2      
317NNAME10049       VIA   -     D0100PA00X+017545Y+103177               S1      
317NNAME10039       VIA   -     D0100PA00X+017590Y+102400               S1      
317GND              J13   -P32  D0300PA00X+017339Y+107189               S0      
317GND              J13   -P31  D0300PA00X+018339Y+107189               S0      
317GND              J13   -P30  D0300PA00X+019339Y+107189               S0      
317GND              J13   -P1   D0300PA00X+017339Y+108252               S0      
317GND              J13   -P2   D0300PA00X+018339Y+108252               S0      
317GND              J13   -P3   D0300PA00X+019339Y+108252               S0      
317GND              CE13  -2    D0360PA00X+019125Y+112286               S0      
317GND              VIA   -     D0200PA00X+017687Y+117626               S3      
317GND              VIA   -     D0200PA00X+017687Y+119034               S3      
317GND              VIA   -     D0200PA00X+017687Y+118374               S3      
317GND              CE14  -2    D0360PA00X+019134Y+120623               S0      
317GND              VIA   -     D0200PA00X+017670Y+119825               S3      
317GND              J14   -P1   D0300PA00X+017339Y+125752               S0      
317GND              J14   -P32  D0300PA00X+017339Y+124689               S0      
317GND              J14   -P2   D0300PA00X+018339Y+125752               S0      
317GND              J14   -P31  D0300PA00X+018339Y+124689               S0      
317GND              J14   -P3   D0300PA00X+019339Y+125752               S0      
317GND              J14   -P30  D0300PA00X+019339Y+124689               S0      
317GND              CE15  -2    D0360PA00X+019185Y+129910               S0      
317GND              CE16  -2    D0360PA00X+019055Y+138097               S0      
317T9_BLAD3_RXD     VIA   -     D0100PA00X+017608Y+140232               S1      
317GND              J15   -P1   D0300PA00X+017339Y+143252               S0      
317GND              J15   -P32  D0300PA00X+017339Y+142189               S0      
317GND              J15   -P2   D0300PA00X+018339Y+143252               S0      
317GND              J15   -P31  D0300PA00X+018339Y+142189               S0      
317GND              J15   -P3   D0300PA00X+019339Y+143252               S0      
317GND              J15   -P30  D0300PA00X+019339Y+142189               S0      
317GND              CE17  -2    D0360PA00X+018946Y+147416               S0      
317GND              VIA   -     D0200PA00X+017786Y+150644               S3      
317GND              VIA   -     D0200PA00X+017786Y+151392               S3      
317GND              VIA   -     D0200PA00X+017786Y+152052               S3      
317GND              VIA   -     D0200PA00X+017769Y+152844               S3      
317GND              VIA   -     D0200PA00X+017769Y+153588               S3      
317GND              VIA   -     D0200PA00X+017769Y+154392               S3      
317GND              VIA   -     D0200PA00X+017769Y+155144               S3      
317GND              CE18  -2    D0360PA00X+019108Y+155728               S0      
317GND              J16   -P32  D0300PA00X+017339Y+159689               S0      
317GND              J16   -P31  D0300PA00X+018339Y+159689               S0      
317GND              J16   -P30  D0300PA00X+019339Y+159689               S0      
317GND              J16   -P1   D0300PA00X+017339Y+160752               S0      
317GND              J16   -P2   D0300PA00X+018339Y+160752               S0      
317GND              J16   -P3   D0300PA00X+019339Y+160752               S0      
317GND              CE19  -2    D0360PA00X+019214Y+164818               S0      
317GND              CE20  -2    D0360PA00X+019161Y+173135               S0      
317T11_BLAD4_TXD    VIA   -     D0100PA00X+017339Y+173605               S1      
317GND              J17   -P32  D0300PA00X+017339Y+177189               S0      
317GND              J17   -P31  D0300PA00X+018339Y+177189               S0      
317GND              J17   -P30  D0300PA00X+019339Y+177189               S0      
317GND              J17   -P1   D0300PA00X+017339Y+178252               S0      
317GND              J17   -P2   D0300PA00X+018339Y+178252               S0      
317GND              J17   -P3   D0300PA00X+019339Y+178252               S0      
317GND              CE22  -2    D0360PA00X+019153Y+182323               S0      
317GND              VIA   -     D0200PA00X+017584Y+188071               S3      
317GND              VIA   -     D0200PA00X+017584Y+188730               S3      
317GND              VIA   -     D0200PA00X+017584Y+187322               S3      
317GND              CE21  -2    D0360PA00X+019029Y+190042               S0      
317GND              VIA   -     D0200PA00X+017567Y+190266               S3      
317GND              VIA   -     D0200PA00X+017567Y+191070               S3      
317GND              VIA   -     D0200PA00X+017567Y+189522               S3      
317GND              VIA   -     D0200PA00X+017567Y+191822               S3      
317GND              J18   -P1   D0300PA00X+017339Y+195752               S0      
317GND              J18   -P32  D0300PA00X+017339Y+194689               S0      
317GND              J18   -P2   D0300PA00X+018339Y+195752               S0      
317GND              J18   -P31  D0300PA00X+018339Y+194689               S0      
317GND              J18   -P3   D0300PA00X+019339Y+195752               S0      
317GND              J18   -P30  D0300PA00X+019339Y+194689               S0      
317GND              CE23  -2    D0360PA00X+019213Y+199873               S0      
317GND              CE24  -2    D0360PA00X+019153Y+204339               S0      
317GND              J7    -P4   D0300PA00X+020339Y+003252               S0      
317GND              J7    -P29  D0300PA00X+020339Y+002189               S0      
317GND              J7    -P5   D0300PA00X+021339Y+003252               S0      
317GND              J7    -P28  D0300PA00X+021339Y+002189               S0      
317P12V             CE1   -1    D0360PA00X+020354Y+007311               S0      
317P12V             CE2   -1    D0360PA00X+020407Y+015205               S0      
317GND              J8    -P29  D0300PA00X+020339Y+019689               S0      
317GND              J8    -P28  D0300PA00X+021339Y+019689               S0      
317GND              J8    -P4   D0300PA00X+020339Y+020752               S0      
317GND              J8    -P5   D0300PA00X+021339Y+020752               S0      
317P12V             CE3   -1    D0360PA00X+020414Y+024757               S0      
317P12V             CE4   -1    D0360PA00X+020460Y+033179               S0      
317GND              J9    -P29  D0300PA00X+020339Y+037189               S0      
317GND              J9    -P28  D0300PA00X+021339Y+037189               S0      
317GND              J9    -P4   D0300PA00X+020339Y+038252               S0      
317GND              J9    -P5   D0300PA00X+021339Y+038252               S0      
317P12V             CE5   -1    D0360PA00X+020354Y+042173               S0      
317P12V             CE6   -1    D0360PA00X+020433Y+050652               S0      
317GND              J10   -P4   D0300PA00X+020339Y+055752               S0      
317GND              J10   -P29  D0300PA00X+020339Y+054689               S0      
317GND              J10   -P5   D0300PA00X+021339Y+055752               S0      
317GND              J10   -P28  D0300PA00X+021339Y+054689               S0      
317P12V             CE8   -1    D0360PA00X+020667Y+059813               S0      
317P12V             CE9   -1    D0360PA00X+020460Y+068165               S0      
317GND              J11   -P4   D0300PA00X+020339Y+073252               S0      
317GND              J11   -P29  D0300PA00X+020339Y+072189               S0      
317GND              J11   -P5   D0300PA00X+021339Y+073252               S0      
317GND              J11   -P28  D0300PA00X+021339Y+072189               S0      
317P12V             CE10  -1    D0360PA00X+020563Y+077453               S0      
317P12V             CE11  -1    D0360PA00X+020539Y+085624               S0      
317GND              J12   -P29  D0300PA00X+020339Y+089689               S0      
317GND              J12   -P28  D0300PA00X+021339Y+089689               S0      
317GND              J12   -P4   D0300PA00X+020339Y+090752               S0      
317GND              J12   -P5   D0300PA00X+021339Y+090752               S0      
317P12V             CE12  -1    D0360PA00X+021009Y+094720               S0      
317P12V             CE7   -1    D0360PA00X+020930Y+103254               S0      
317GND              J13   -P29  D0300PA00X+020339Y+107189               S0      
317GND              J13   -P28  D0300PA00X+021339Y+107189               S0      
317GND              J13   -P4   D0300PA00X+020339Y+108252               S0      
317GND              J13   -P5   D0300PA00X+021339Y+108252               S0      
317P12V             CE13  -1    D0360PA00X+020503Y+112286               S0      
317P12V             CE14  -1    D0360PA00X+020512Y+120623               S0      
317GND              J14   -P4   D0300PA00X+020339Y+125752               S0      
317GND              J14   -P29  D0300PA00X+020339Y+124689               S0      
317GND              J14   -P5   D0300PA00X+021339Y+125752               S0      
317GND              J14   -P28  D0300PA00X+021339Y+124689               S0      
317P12V             VIA   -     D0200PA00X+021921Y+128727               S3      
317P12V             CE15  -1    D0360PA00X+020563Y+129910               S0      
317P12V             VIA   -     D0200PA00X+021921Y+130198               S3      
317P12V             VIA   -     D0200PA00X+021935Y+130892               S3      
317P12V             VIA   -     D0200PA00X+021921Y+129449               S3      
317P12V             VIA   -     D0200PA00X+021918Y+132429               S3      
317P12V             VIA   -     D0200PA00X+021918Y+133232               S3      
317P12V             VIA   -     D0200PA00X+021918Y+131684               S3      
317P12V             VIA   -     D0200PA00X+021918Y+133984               S3      
317P12V             CE16  -1    D0360PA00X+020433Y+138097               S0      
317GND              J15   -P4   D0300PA00X+020339Y+143252               S0      
317GND              J15   -P29  D0300PA00X+020339Y+142189               S0      
317GND              J15   -P5   D0300PA00X+021339Y+143252               S0      
317GND              J15   -P28  D0300PA00X+021339Y+142189               S0      
317P12V             CE17  -1    D0360PA00X+020324Y+147416               S0      
317P12V             CE18  -1    D0360PA00X+020486Y+155728               S0      
317GND              J16   -P29  D0300PA00X+020339Y+159689               S0      
317GND              J16   -P28  D0300PA00X+021339Y+159689               S0      
317GND              J16   -P4   D0300PA00X+020339Y+160752               S0      
317GND              J16   -P5   D0300PA00X+021339Y+160752               S0      
317P12V             CE19  -1    D0360PA00X+020592Y+164818               S0      
317P12V             CE20  -1    D0360PA00X+020539Y+173135               S0      
317GND              J17   -P29  D0300PA00X+020339Y+177189               S0      
317GND              J17   -P28  D0300PA00X+021339Y+177189               S0      
317GND              J17   -P4   D0300PA00X+020339Y+178252               S0      
317GND              J17   -P5   D0300PA00X+021339Y+178252               S0      
317P12V             CE22  -1    D0360PA00X+020531Y+182323               S0      
317P12V             CE21  -1    D0360PA00X+020407Y+190042               S0      
317GND              J18   -P4   D0300PA00X+020339Y+195752               S0      
317GND              J18   -P29  D0300PA00X+020339Y+194689               S0      
317GND              J18   -P5   D0300PA00X+021339Y+195752               S0      
317GND              J18   -P28  D0300PA00X+021339Y+194689               S0      
317P12V             CE23  -1    D0360PA00X+020591Y+199873               S0      
317P12V             CE24  -1    D0360PA00X+020531Y+204339               S0      
317GND              VIA   -     D0100PA00X+020999Y+208361               S3      
317GND              VIA   -     D0100PA00X+022522Y+000300               S3      
317GND              J7    -P6   D0300PA00X+022339Y+003252               S0      
317GND              J7    -P27  D0300PA00X+022339Y+002189               S0      
317GND              J7    -P7   D0300PA00X+023339Y+003252               S0      
317GND              J7    -P26  D0300PA00X+023339Y+002189               S0      
317GND              J7    -P8   D0300PA00X+024339Y+003252               S0      
317GND              J7    -P25  D0300PA00X+024339Y+002189               S0      
317GND              VIA   -     D0200PA00X+024096Y+005700               S3      
317GND              VIA   -     D0200PA00X+024096Y+006448               S3      
317GND              VIA   -     D0200PA00X+024078Y+007900               S3      
317GND              VIA   -     D0200PA00X+024096Y+007108               S3      
317GND              VIA   -     D0200PA00X+024078Y+009448               S3      
317GND              VIA   -     D0200PA00X+024078Y+010199               S3      
317GND              VIA   -     D0200PA00X+024078Y+008644               S3      
317P12V             VIA   -     D0200PA00X+024374Y+015396               S3      
317P12V             VIA   -     D0200PA00X+022273Y+015396               S3      
317P12V             VIA   -     D0200PA00X+023270Y+015396               S3      
317P12V             VIA   -     D0200PA00X+024374Y+017013               S3      
317P12V             VIA   -     D0200PA00X+024374Y+016169               S3      
317P12V             VIA   -     D0200PA00X+022273Y+017013               S3      
317P12V             VIA   -     D0200PA00X+022273Y+016169               S3      
317P12V             VIA   -     D0200PA00X+023270Y+017013               S3      
317P12V             VIA   -     D0200PA00X+023270Y+016169               S3      
317GND              J8    -P27  D0300PA00X+022339Y+019689               S0      
317GND              J8    -P26  D0300PA00X+023339Y+019689               S0      
317GND              J8    -P25  D0300PA00X+024339Y+019689               S0      
317GND              J8    -P6   D0300PA00X+022339Y+020752               S0      
317GND              J8    -P7   D0300PA00X+023339Y+020752               S0      
317GND              J8    -P8   D0300PA00X+024339Y+020752               S0      
317GND              VIA   -     D0200PA00X+023654Y+024500               S3      
317GND              VIA   -     D0200PA00X+022771Y+023778               S3      
317GND              VIA   -     D0200PA00X+022771Y+024500               S3      
317GND              VIA   -     D0200PA00X+024403Y+024500               S3      
317GND              VIA   -     D0200PA00X+023654Y+025907               S3      
317GND              VIA   -     D0200PA00X+023637Y+026699               S3      
317GND              VIA   -     D0200PA00X+023637Y+027444               S3      
317GND              VIA   -     D0200PA00X+022771Y+025907               S3      
317GND              VIA   -     D0200PA00X+022754Y+026699               S3      
317GND              VIA   -     D0200PA00X+022754Y+027444               S3      
317GND              VIA   -     D0200PA00X+024403Y+025907               S3      
317GND              VIA   -     D0200PA00X+024386Y+026699               S3      
317GND              VIA   -     D0200PA00X+024386Y+027444               S3      
317GND              VIA   -     D0200PA00X+023654Y+025248               S3      
317GND              VIA   -     D0200PA00X+022771Y+025248               S3      
317GND              VIA   -     D0200PA00X+024403Y+025248               S3      
317GND              VIA   -     D0200PA00X+023637Y+028999               S3      
317GND              VIA   -     D0200PA00X+022754Y+028999               S3      
317GND              VIA   -     D0200PA00X+024386Y+028999               S3      
317GND              VIA   -     D0200PA00X+023637Y+028247               S3      
317GND              VIA   -     D0200PA00X+022754Y+028247               S3      
317GND              VIA   -     D0200PA00X+024386Y+028247               S3      
317GND              J9    -P27  D0300PA00X+022339Y+037189               S0      
317GND              J9    -P26  D0300PA00X+023339Y+037189               S0      
317GND              J9    -P25  D0300PA00X+024339Y+037189               S0      
317GND              J9    -P6   D0300PA00X+022339Y+038252               S0      
317GND              J9    -P7   D0300PA00X+023339Y+038252               S0      
317GND              J9    -P8   D0300PA00X+024339Y+038252               S0      
317P12V             VIA   -     D0200PA00X+023975Y+040739               S3      
317P12V             VIA   -     D0200PA00X+023975Y+039688               S3      
317P12V             VIA   -     D0200PA00X+023975Y+041790               S3      
317GND              VIA   -     D0200PA00X+023255Y+046108               S3      
317GND              VIA   -     D0200PA00X+024137Y+048238               S3      
317GND              VIA   -     D0200PA00X+024120Y+049030               S3      
317GND              VIA   -     D0200PA00X+023255Y+048238               S3      
317GND              VIA   -     D0200PA00X+023238Y+049030               S3      
317GND              VIA   -     D0200PA00X+024137Y+046830               S3      
317GND              VIA   -     D0200PA00X+024137Y+047579               S3      
317GND              VIA   -     D0200PA00X+023255Y+046830               S3      
317GND              VIA   -     D0200PA00X+023255Y+047579               S3      
317GND              VIA   -     D0200PA00X+024120Y+051330               S3      
317GND              VIA   -     D0200PA00X+023238Y+051330               S3      
317GND              VIA   -     D0200PA00X+024120Y+049774               S3      
317GND              VIA   -     D0200PA00X+023238Y+049774               S3      
317GND              VIA   -     D0200PA00X+024120Y+050578               S3      
317GND              VIA   -     D0200PA00X+023238Y+050578               S3      
317GND              J10   -P6   D0300PA00X+022339Y+055752               S0      
317GND              J10   -P27  D0300PA00X+022339Y+054689               S0      
317GND              J10   -P7   D0300PA00X+023339Y+055752               S0      
317GND              J10   -P26  D0300PA00X+023339Y+054689               S0      
317GND              J10   -P8   D0300PA00X+024339Y+055752               S0      
317GND              J10   -P25  D0300PA00X+024339Y+054689               S0      
317GND              VIA   -     D0200PA00X+023096Y+060811               S3      
317GND              VIA   -     D0200PA00X+023839Y+060811               S3      
317GND              VIA   -     D0200PA00X+023096Y+060151               S3      
317GND              VIA   -     D0200PA00X+023839Y+060151               S3      
317GND              VIA   -     D0200PA00X+023839Y+059403               S3      
317GND              VIA   -     D0200PA00X+023096Y+059403               S3      
317GND              VIA   -     D0200PA00X+023079Y+063151               S3      
317GND              VIA   -     D0200PA00X+023822Y+063151               S3      
317GND              VIA   -     D0200PA00X+023079Y+062347               S3      
317GND              VIA   -     D0200PA00X+023822Y+062347               S3      
317GND              VIA   -     D0200PA00X+023079Y+061603               S3      
317GND              VIA   -     D0200PA00X+023822Y+061603               S3      
317GND              VIA   -     D0200PA00X+023079Y+063902               S3      
317GND              VIA   -     D0200PA00X+023822Y+063902               S3      
317GND              J11   -P6   D0300PA00X+022339Y+073252               S0      
317GND              J11   -P27  D0300PA00X+022339Y+072189               S0      
317GND              J11   -P7   D0300PA00X+023339Y+073252               S0      
317GND              J11   -P26  D0300PA00X+023339Y+072189               S0      
317GND              J11   -P8   D0300PA00X+024339Y+073252               S0      
317GND              J11   -P25  D0300PA00X+024339Y+072189               S0      
317P12V             VIA   -     D0200PA00X+024398Y+075478               S3      
317P12V             VIA   -     D0200PA00X+023401Y+075478               S3      
317P12V             VIA   -     D0200PA00X+024398Y+076251               S3      
317P12V             VIA   -     D0200PA00X+024398Y+077095               S3      
317P12V             VIA   -     D0200PA00X+023401Y+076251               S3      
317P12V             VIA   -     D0200PA00X+023401Y+077095               S3      
317GND              J12   -P27  D0300PA00X+022339Y+089689               S0      
317GND              J12   -P26  D0300PA00X+023339Y+089689               S0      
317GND              J12   -P25  D0300PA00X+024339Y+089689               S0      
317GND              J12   -P6   D0300PA00X+022339Y+090752               S0      
317GND              J12   -P7   D0300PA00X+023339Y+090752               S0      
317GND              J12   -P8   D0300PA00X+024339Y+090752               S0      
317GND              VIA   -     D0200PA00X+023134Y+095967               S3      
317GND              VIA   -     D0200PA00X+023877Y+095967               S3      
317GND              VIA   -     D0200PA00X+023877Y+096716               S3      
317GND              VIA   -     D0200PA00X+023877Y+097375               S3      
317GND              VIA   -     D0200PA00X+023134Y+097375               S3      
317GND              VIA   -     D0200PA00X+023134Y+096716               S3      
317GND              VIA   -     D0200PA00X+023877Y+095245               S3      
317GND              VIA   -     D0200PA00X+023134Y+095245               S3      
317GND              VIA   -     D0200PA00X+023860Y+098167               S3      
317GND              VIA   -     D0200PA00X+023117Y+098167               S3      
317GND              VIA   -     D0200PA00X+023860Y+099715               S3      
317GND              VIA   -     D0200PA00X+023860Y+098911               S3      
317GND              VIA   -     D0200PA00X+023117Y+099715               S3      
317GND              VIA   -     D0200PA00X+023117Y+098911               S3      
317GND              VIA   -     D0200PA00X+023860Y+100467               S3      
317GND              VIA   -     D0200PA00X+023117Y+100467               S3      
317GND              J13   -P27  D0300PA00X+022339Y+107189               S0      
317GND              J13   -P26  D0300PA00X+023339Y+107189               S0      
317GND              J13   -P25  D0300PA00X+024339Y+107189               S0      
317GND              J13   -P6   D0300PA00X+022339Y+108252               S0      
317GND              J13   -P7   D0300PA00X+023339Y+108252               S0      
317GND              J13   -P8   D0300PA00X+024339Y+108252               S0      
317GND              VIA   -     D0200PA00X+023866Y+121530               S3      
317GND              VIA   -     D0200PA00X+023123Y+121530               S3      
317GND              VIA   -     D0200PA00X+023866Y+120778               S3      
317GND              VIA   -     D0200PA00X+023866Y+119974               S3      
317GND              VIA   -     D0200PA00X+023123Y+120778               S3      
317GND              VIA   -     D0200PA00X+023123Y+119974               S3      
317GND              J14   -P6   D0300PA00X+022339Y+125752               S0      
317GND              J14   -P27  D0300PA00X+022339Y+124689               S0      
317GND              J14   -P7   D0300PA00X+023339Y+125752               S0      
317GND              J14   -P26  D0300PA00X+023339Y+124689               S0      
317GND              J14   -P8   D0300PA00X+024339Y+125752               S0      
317GND              J14   -P25  D0300PA00X+024339Y+124689               S0      
317P12V             VIA   -     D0200PA00X+022664Y+128727               S3      
317P12V             VIA   -     D0200PA00X+022664Y+130198               S3      
317P12V             VIA   -     D0200PA00X+023547Y+130198               S3      
317P12V             VIA   -     D0200PA00X+022678Y+130892               S3      
317P12V             VIA   -     D0200PA00X+023560Y+130892               S3      
317P12V             VIA   -     D0200PA00X+024296Y+130198               S3      
317P12V             VIA   -     D0200PA00X+024310Y+130892               S3      
317P12V             VIA   -     D0200PA00X+022664Y+129449               S3      
317P12V             VIA   -     D0200PA00X+023547Y+129449               S3      
317P12V             VIA   -     D0200PA00X+024296Y+129449               S3      
317P12V             VIA   -     D0200PA00X+022661Y+132429               S3      
317P12V             VIA   -     D0200PA00X+023543Y+132429               S3      
317P12V             VIA   -     D0200PA00X+022661Y+133232               S3      
317P12V             VIA   -     D0200PA00X+023543Y+133232               S3      
317P12V             VIA   -     D0200PA00X+024293Y+132429               S3      
317P12V             VIA   -     D0200PA00X+024293Y+133232               S3      
317P12V             VIA   -     D0200PA00X+022661Y+131684               S3      
317P12V             VIA   -     D0200PA00X+023543Y+131684               S3      
317P12V             VIA   -     D0200PA00X+024293Y+131684               S3      
317P12V             VIA   -     D0200PA00X+022661Y+133984               S3      
317P12V             VIA   -     D0200PA00X+023543Y+133984               S3      
317P12V             VIA   -     D0200PA00X+024293Y+133984               S3      
317GND              J15   -P6   D0300PA00X+022339Y+143252               S0      
317GND              J15   -P27  D0300PA00X+022339Y+142189               S0      
317GND              J15   -P7   D0300PA00X+023339Y+143252               S0      
317GND              J15   -P26  D0300PA00X+023339Y+142189               S0      
317GND              J15   -P8   D0300PA00X+024339Y+143252               S0      
317GND              J15   -P25  D0300PA00X+024339Y+142189               S0      
317GND              J16   -P27  D0300PA00X+022339Y+159689               S0      
317GND              J16   -P26  D0300PA00X+023339Y+159689               S0      
317GND              J16   -P25  D0300PA00X+024339Y+159689               S0      
317GND              J16   -P6   D0300PA00X+022339Y+160752               S0      
317GND              J16   -P7   D0300PA00X+023339Y+160752               S0      
317GND              J16   -P8   D0300PA00X+024339Y+160752               S0      
317GND              VIA   -     D0200PA00X+022513Y+166317               S3      
317GND              VIA   -     D0200PA00X+024138Y+167039               S3      
317GND              VIA   -     D0200PA00X+023256Y+166317               S3      
317GND              VIA   -     D0200PA00X+023256Y+167039               S3      
317GND              VIA   -     D0200PA00X+022513Y+167039               S3      
317GND              VIA   -     D0200PA00X+024121Y+169983               S3      
317GND              VIA   -     D0200PA00X+024138Y+167787               S3      
317GND              VIA   -     D0200PA00X+024121Y+169238               S3      
317GND              VIA   -     D0200PA00X+024138Y+168447               S3      
317GND              VIA   -     D0200PA00X+023256Y+168447               S3      
317GND              VIA   -     D0200PA00X+023256Y+167787               S3      
317GND              VIA   -     D0200PA00X+023239Y+169238               S3      
317GND              VIA   -     D0200PA00X+023239Y+169983               S3      
317GND              VIA   -     D0200PA00X+022513Y+168447               S3      
317GND              VIA   -     D0200PA00X+022513Y+167787               S3      
317GND              VIA   -     D0200PA00X+022496Y+169238               S3      
317GND              VIA   -     D0200PA00X+022496Y+169983               S3      
317GND              VIA   -     D0200PA00X+024121Y+171538               S3      
317GND              VIA   -     D0200PA00X+024121Y+170786               S3      
317GND              VIA   -     D0200PA00X+023239Y+170786               S3      
317GND              VIA   -     D0200PA00X+023239Y+171538               S3      
317GND              VIA   -     D0200PA00X+022496Y+170786               S3      
317GND              VIA   -     D0200PA00X+022496Y+171538               S3      
317GND              J17   -P27  D0300PA00X+022339Y+177189               S0      
317GND              J17   -P26  D0300PA00X+023339Y+177189               S0      
317GND              J17   -P25  D0300PA00X+024339Y+177189               S0      
317GND              J17   -P6   D0300PA00X+022339Y+178252               S0      
317GND              J17   -P7   D0300PA00X+023339Y+178252               S0      
317GND              J17   -P8   D0300PA00X+024339Y+178252               S0      
317GND              J18   -P6   D0300PA00X+022339Y+195752               S0      
317GND              J18   -P27  D0300PA00X+022339Y+194689               S0      
317GND              J18   -P7   D0300PA00X+023339Y+195752               S0      
317GND              J18   -P26  D0300PA00X+023339Y+194689               S0      
317GND              J18   -P8   D0300PA00X+024339Y+195752               S0      
317GND              J18   -P25  D0300PA00X+024339Y+194689               S0      
317P12V             VIA   -     D0200PA00X+022457Y+203148               S3      
317P12V             VIA   -     D0200PA00X+023454Y+203148               S3      
317P12V             VIA   -     D0200PA00X+022457Y+202097               S3      
317P12V             VIA   -     D0200PA00X+023454Y+202097               S3      
317P12V             VIA   -     D0200PA00X+022457Y+205905               S3      
317P12V             VIA   -     D0200PA00X+023454Y+205132               S3      
317P12V             VIA   -     D0200PA00X+023454Y+205905               S3      
317P12V             VIA   -     D0200PA00X+022457Y+204199               S3      
317P12V             VIA   -     D0200PA00X+022457Y+205132               S3      
317P12V             VIA   -     D0200PA00X+023454Y+204199               S3      
317P12V             VIA   -     D0200PA00X+023454Y+206749               S3      
317P12V             VIA   -     D0200PA00X+022457Y+206749               S3      
317P12V             J7    -P24  D0300PA00X+025339Y+002189               S0      
317P12V             J7    -P9   D0300PA00X+025339Y+003252               S0      
317P12V             J7    -P23  D0300PA00X+026339Y+002189               S0      
317P12V             J7    -P10  D0300PA00X+026339Y+003252               S0      
317P12V             VIA   -     D0200PA00X+025657Y+005494               S3      
317P12V             VIA   -     D0200PA00X+026410Y+005494               S3      
317P12V             VIA   -     D0200PA00X+025657Y+004557               S3      
317P12V             VIA   -     D0200PA00X+026410Y+004557               S3      
317GND              VIA   -     D0200PA00X+024845Y+005700               S3      
317P12V             VIA   -     D0200PA00X+025657Y+006545               S3      
317P12V             VIA   -     D0200PA00X+026410Y+006545               S3      
317GND              VIA   -     D0200PA00X+024845Y+006448               S3      
317GND              VIA   -     D0200PA00X+024828Y+007900               S3      
317GND              VIA   -     D0200PA00X+024845Y+007108               S3      
317GND              VIA   -     D0200PA00X+024828Y+009448               S3      
317GND              VIA   -     D0200PA00X+024828Y+010199               S3      
317GND              VIA   -     D0200PA00X+024828Y+008644               S3      
327P12V             R111  -2          A01X+026469Y+012823X0180Y0200R180 S2      
327NNAME10043       R111  -1          A01X+026154Y+012823X0180Y0200R180 S2      
327GND              R112  -2          A01X+026493Y+011556X0180Y0200R180 S2      
327NNAME10031       R112  -1          A01X+026178Y+011556X0180Y0200R180 S2      
317GND              VIA   -     D0100PA00X+026763Y+011556               S3      
317NNAME10043       VIA   -     D0100PA00X+025695Y+012828               S1      
317NNAME10031       VIA   -     D0100PA00X+025713Y+011556               S1      
317P12V             VIA   -     D0200PA00X+026486Y+015396               S3      
317P12V             VIA   -     D0200PA00X+025308Y+015396               S3      
317P12V             VIA   -     D0200PA00X+026486Y+017013               S3      
317P12V             VIA   -     D0200PA00X+026486Y+016169               S3      
317P12V             VIA   -     D0200PA00X+025308Y+017013               S3      
317P12V             VIA   -     D0200PA00X+025308Y+016169               S3      
317P12V             J8    -P24  D0300PA00X+025339Y+019689               S0      
317P12V             J8    -P23  D0300PA00X+026339Y+019689               S0      
317P12V             J8    -P9   D0300PA00X+025339Y+020752               S0      
317P12V             J8    -P10  D0300PA00X+026339Y+020752               S0      
317P12V             VIA   -     D0200PA00X+026460Y+022166               S3      
317P12V             VIA   -     D0200PA00X+025282Y+022166               S3      
317P12V             VIA   -     D0200PA00X+026460Y+024268               S3      
317P12V             VIA   -     D0200PA00X+026460Y+023218               S3      
317P12V             VIA   -     D0200PA00X+025282Y+024268               S3      
317P12V             VIA   -     D0200PA00X+025282Y+023218               S3      
317P12V             VIA   -     D0200PA00X+026460Y+026819               S3      
317P12V             VIA   -     D0200PA00X+026460Y+025975               S3      
317P12V             VIA   -     D0200PA00X+026460Y+025202               S3      
317P12V             VIA   -     D0200PA00X+025282Y+026819               S3      
317P12V             VIA   -     D0200PA00X+025282Y+025202               S3      
317P12V             VIA   -     D0200PA00X+025282Y+025975               S3      
317P12V             J9    -P24  D0300PA00X+025339Y+037189               S0      
317P12V             J9    -P23  D0300PA00X+026339Y+037189               S0      
317P12V             J9    -P9   D0300PA00X+025339Y+038252               S0      
317P12V             J9    -P10  D0300PA00X+026339Y+038252               S0      
317P12V             VIA   -     D0200PA00X+026604Y+040715               S3      
317P12V             VIA   -     D0200PA00X+026604Y+039663               S3      
317P12V             VIA   -     D0200PA00X+026604Y+041765               S3      
317P12V             VIA   -     D0200PA00X+025757Y+039663               S3      
317P12V             VIA   -     D0200PA00X+025757Y+040715               S3      
317P12V             VIA   -     D0200PA00X+024871Y+040754               S3      
317P12V             VIA   -     D0200PA00X+024871Y+039702               S3      
317P12V             VIA   -     D0200PA00X+025757Y+041765               S3      
317P12V             VIA   -     D0200PA00X+024871Y+041804               S3      
317NNAME10034       VIA   -     D0100PA00X+026572Y+046310               S1      
317GND              VIA   -     D0200PA00X+024887Y+048238               S3      
317GND              VIA   -     D0200PA00X+024870Y+049030               S3      
317GND              VIA   -     D0200PA00X+024887Y+046830               S3      
317GND              VIA   -     D0200PA00X+024887Y+047579               S3      
317NNAME10045       VIA   -     D0100PA00X+026574Y+047368               S1      
317GND              VIA   -     D0200PA00X+024870Y+051330               S3      
317GND              VIA   -     D0200PA00X+024870Y+049774               S3      
317GND              VIA   -     D0200PA00X+024870Y+050578               S3      
317P12V             J10   -P24  D0300PA00X+025339Y+054689               S0      
317P12V             J10   -P9   D0300PA00X+025339Y+055752               S0      
317P12V             J10   -P23  D0300PA00X+026339Y+054689               S0      
317P12V             J10   -P10  D0300PA00X+026339Y+055752               S0      
317P12V             VIA   -     D0200PA00X+026717Y+058144               S3      
317P12V             VIA   -     D0200PA00X+026717Y+057264               S3      
317P12V             VIA   -     D0200PA00X+026717Y+060901               S3      
317P12V             VIA   -     D0200PA00X+026717Y+060128               S3      
317P12V             VIA   -     D0200PA00X+026717Y+059195               S3      
317GND              VIA   -     D0200PA00X+025471Y+060811               S3      
317GND              VIA   -     D0200PA00X+025471Y+060151               S3      
317GND              VIA   -     D0200PA00X+025471Y+059403               S3      
317GND              VIA   -     D0200PA00X+024721Y+060811               S3      
317GND              VIA   -     D0200PA00X+024721Y+060151               S3      
317GND              VIA   -     D0200PA00X+024721Y+059403               S3      
317P12V             VIA   -     D0200PA00X+026717Y+061745               S3      
317GND              VIA   -     D0200PA00X+025454Y+063151               S3      
317GND              VIA   -     D0200PA00X+025454Y+062347               S3      
317GND              VIA   -     D0200PA00X+025454Y+061603               S3      
317GND              VIA   -     D0200PA00X+024704Y+063151               S3      
317GND              VIA   -     D0200PA00X+024704Y+062347               S3      
317GND              VIA   -     D0200PA00X+024704Y+061603               S3      
317GND              VIA   -     D0200PA00X+026743Y+062432               S3      
317GND              VIA   -     D0200PA00X+025454Y+063902               S3      
317GND              VIA   -     D0200PA00X+024704Y+063902               S3      
317P12V             J11   -P24  D0300PA00X+025339Y+072189               S0      
317P12V             J11   -P9   D0300PA00X+025339Y+073252               S0      
317P12V             J11   -P23  D0300PA00X+026339Y+072189               S0      
317P12V             J11   -P10  D0300PA00X+026339Y+073252               S0      
317P12V             VIA   -     D0200PA00X+025502Y+075478               S3      
317P12V             VIA   -     D0200PA00X+025502Y+076251               S3      
317P12V             VIA   -     D0200PA00X+025502Y+077095               S3      
327P12V             R119  -2          A01X+026418Y+082360X0180Y0200R180 S2      
327NNAME10046       R119  -1          A01X+026103Y+082360X0180Y0200R180 S2      
327GND              R120  -2          A01X+026434Y+081217X0180Y0200R180 S2      
327NNAME10036       R120  -1          A01X+026119Y+081217X0180Y0200R180 S2      
317NNAME10046       VIA   -     D0100PA00X+025584Y+082363               S1      
317NNAME10036       VIA   -     D0100PA00X+025569Y+081219               S1      
317P12V             VIA   -     D0200PA00X+026317Y+085516               S3      
317P12V             VIA   -     D0200PA00X+026317Y+086289               S3      
317P12V             VIA   -     D0200PA00X+025140Y+086289               S3      
317P12V             VIA   -     D0200PA00X+025140Y+085516               S3      
317P12V             VIA   -     D0200PA00X+025140Y+087133               S3      
317P12V             VIA   -     D0200PA00X+026317Y+087133               S3      
317P12V             J12   -P24  D0300PA00X+025339Y+089689               S0      
317P12V             J12   -P23  D0300PA00X+026339Y+089689               S0      
317P12V             J12   -P9   D0300PA00X+025339Y+090752               S0      
317P12V             J12   -P10  D0300PA00X+026339Y+090752               S0      
317P12V             VIA   -     D0200PA00X+026277Y+094934               S3      
317P12V             VIA   -     D0200PA00X+026277Y+096711               S3      
317P12V             VIA   -     D0200PA00X+026277Y+095986               S3      
317P12V             VIA   -     D0200PA00X+026262Y+097439               S3      
317GND              VIA   -     D0200PA00X+025509Y+095967               S3      
317GND              VIA   -     D0200PA00X+025509Y+097375               S3      
317GND              VIA   -     D0200PA00X+025509Y+096716               S3      
317GND              VIA   -     D0200PA00X+024759Y+095967               S3      
317GND              VIA   -     D0200PA00X+024759Y+097375               S3      
317GND              VIA   -     D0200PA00X+024759Y+096716               S3      
317P12V             VIA   -     D0200PA00X+026262Y+099055               S3      
317P12V             VIA   -     D0200PA00X+026262Y+098211               S3      
317GND              VIA   -     D0200PA00X+025492Y+098167               S3      
317GND              VIA   -     D0200PA00X+025492Y+099715               S3      
317GND              VIA   -     D0200PA00X+025492Y+098911               S3      
317GND              VIA   -     D0200PA00X+024742Y+098167               S3      
317GND              VIA   -     D0200PA00X+024742Y+099715               S3      
317GND              VIA   -     D0200PA00X+024742Y+098911               S3      
317GND              VIA   -     D0200PA00X+025492Y+100467               S3      
317GND              VIA   -     D0200PA00X+024742Y+100467               S3      
317P12V             J13   -P24  D0300PA00X+025339Y+107189               S0      
317P12V             J13   -P23  D0300PA00X+026339Y+107189               S0      
317P12V             J13   -P9   D0300PA00X+025339Y+108252               S0      
317P12V             J13   -P10  D0300PA00X+026339Y+108252               S0      
317P12V             VIA   -     D0200PA00X+026122Y+112436               S3      
317P12V             VIA   -     D0200PA00X+026122Y+113488               S3      
317P12V             VIA   -     D0200PA00X+025125Y+112436               S3      
317P12V             VIA   -     D0200PA00X+025125Y+113488               S3      
317P12V             VIA   -     D0200PA00X+026122Y+114538               S3      
317P12V             VIA   -     D0200PA00X+025125Y+114538               S3      
317GND              VIA   -     D0200PA00X+025498Y+121530               S3      
317GND              VIA   -     D0200PA00X+024748Y+121530               S3      
317GND              VIA   -     D0200PA00X+025498Y+120778               S3      
317GND              VIA   -     D0200PA00X+025498Y+119974               S3      
317GND              VIA   -     D0200PA00X+024748Y+120778               S3      
317GND              VIA   -     D0200PA00X+024748Y+119974               S3      
317P12V             J14   -P24  D0300PA00X+025339Y+124689               S0      
317P12V             J14   -P9   D0300PA00X+025339Y+125752               S0      
317P12V             J14   -P23  D0300PA00X+026339Y+124689               S0      
317P12V             J14   -P10  D0300PA00X+026339Y+125752               S0      
317P12V             VIA   -     D0200PA00X+025958Y+127243               S3      
317P12V             VIA   -     D0200PA00X+025958Y+128295               S3      
317P12V             VIA   -     D0200PA00X+025958Y+129345               S3      
317P12V             VIA   -     D0200PA00X+025958Y+130279               S3      
317P12V             VIA   -     D0200PA00X+025958Y+131052               S3      
317P12V             VIA   -     D0200PA00X+025958Y+131895               S3      
317P12V             J15   -P24  D0300PA00X+025339Y+142189               S0      
317P12V             J15   -P9   D0300PA00X+025339Y+143252               S0      
317P12V             J15   -P23  D0300PA00X+026339Y+142189               S0      
317P12V             J15   -P10  D0300PA00X+026339Y+143252               S0      
317P12V             VIA   -     D0200PA00X+026394Y+154801               S3      
317P12V             VIA   -     D0200PA00X+026394Y+153414               S3      
317P12V             VIA   -     D0200PA00X+026394Y+154106               S3      
317P12V             J16   -P24  D0300PA00X+025339Y+159689               S0      
317P12V             J16   -P23  D0300PA00X+026339Y+159689               S0      
317P12V             J16   -P9   D0300PA00X+025339Y+160752               S0      
317P12V             J16   -P10  D0300PA00X+026339Y+160752               S0      
317P12V             VIA   -     D0200PA00X+026156Y+162182               S3      
317P12V             VIA   -     D0200PA00X+026156Y+164284               S3      
317P12V             VIA   -     D0200PA00X+026156Y+163234               S3      
317P12V             VIA   -     D0200PA00X+026156Y+166835               S3      
317P12V             VIA   -     D0200PA00X+026156Y+165991               S3      
317P12V             VIA   -     D0200PA00X+026156Y+165218               S3      
317GND              VIA   -     D0200PA00X+024888Y+167039               S3      
317P12V             VIA   -     D0200PA00X+026576Y+169761               S3      
317P12V             VIA   -     D0200PA00X+025472Y+169761               S3      
317P12V             VIA   -     D0200PA00X+026576Y+167659               S3      
317P12V             VIA   -     D0200PA00X+026576Y+168711               S3      
317P12V             VIA   -     D0200PA00X+025472Y+168711               S3      
317P12V             VIA   -     D0200PA00X+025472Y+167659               S3      
317GND              VIA   -     D0200PA00X+024871Y+169983               S3      
317GND              VIA   -     D0200PA00X+024888Y+167787               S3      
317GND              VIA   -     D0200PA00X+024888Y+168447               S3      
317GND              VIA   -     D0200PA00X+024871Y+169238               S3      
317P12V             VIA   -     D0200PA00X+025446Y+172214               S3      
317P12V             VIA   -     D0200PA00X+026550Y+172214               S3      
317P12V             VIA   -     D0200PA00X+026576Y+171468               S3      
317P12V             VIA   -     D0200PA00X+025472Y+171468               S3      
317P12V             VIA   -     D0200PA00X+025472Y+170695               S3      
317P12V             VIA   -     D0200PA00X+026576Y+170695               S3      
317GND              VIA   -     D0200PA00X+024871Y+170786               S3      
317GND              VIA   -     D0200PA00X+024871Y+171538               S3      
317P12V             J17   -P24  D0300PA00X+025339Y+177189               S0      
317P12V             J17   -P23  D0300PA00X+026339Y+177189               S0      
317P12V             J17   -P9   D0300PA00X+025339Y+178252               S0      
317P12V             J17   -P10  D0300PA00X+026339Y+178252               S0      
317P12V             VIA   -     D0200PA00X+025864Y+181907               S3      
317P12V             VIA   -     D0200PA00X+025864Y+181212               S3      
317P12V             VIA   -     D0200PA00X+025864Y+180520               S3      
317P12V             VIA   -     D0200PA00X+025047Y+181907               S3      
317P12V             VIA   -     D0200PA00X+025047Y+181212               S3      
317P12V             VIA   -     D0200PA00X+025047Y+180520               S3      
317P12V             VIA   -     D0200PA00X+026740Y+181908               S3      
317P12V             VIA   -     D0200PA00X+026740Y+180521               S3      
317P12V             VIA   -     D0200PA00X+026740Y+181212               S3      
317P12V             VIA   -     D0200PA00X+025846Y+182622               S3      
317P12V             VIA   -     D0200PA00X+025029Y+182622               S3      
317P12V             VIA   -     D0200PA00X+026704Y+182622               S3      
317P12V             VIA   -     D0200PA00X+025846Y+184009               S3      
317P12V             VIA   -     D0200PA00X+025846Y+183314               S3      
317P12V             VIA   -     D0200PA00X+026704Y+183314               S3      
317P12V             VIA   -     D0200PA00X+026704Y+184009               S3      
317P12V             VIA   -     D0200PA00X+025029Y+183314               S3      
317P12V             VIA   -     D0200PA00X+025029Y+184009               S3      
317P12V             J18   -P24  D0300PA00X+025339Y+194689               S0      
317P12V             J18   -P9   D0300PA00X+025339Y+195752               S0      
317P12V             J18   -P23  D0300PA00X+026339Y+194689               S0      
317P12V             J18   -P10  D0300PA00X+026339Y+195752               S0      
317P12V             VIA   -     D0200PA00X+024558Y+203148               S3      
317P12V             VIA   -     D0200PA00X+024558Y+202097               S3      
317P12V             VIA   -     D0200PA00X+025834Y+202097               S3      
317P12V             VIA   -     D0200PA00X+025834Y+203148               S3      
317P12V             VIA   -     D0200PA00X+024558Y+204199               S3      
317P12V             VIA   -     D0200PA00X+024558Y+205132               S3      
317P12V             VIA   -     D0200PA00X+024558Y+205905               S3      
317P12V             VIA   -     D0200PA00X+025834Y+205132               S3      
317P12V             VIA   -     D0200PA00X+025834Y+205905               S3      
317P12V             VIA   -     D0200PA00X+025834Y+204199               S3      
317P12V             VIA   -     D0200PA00X+025834Y+206749               S3      
317P12V             VIA   -     D0200PA00X+024558Y+206749               S3      
317GND              VIA   -     D0100PA00X+025999Y+208361               S3      
317GND              VIA   -     D0100PA00X+027522Y+000300               S3      
317P12V             J7    -P22  D0300PA00X+027339Y+002189               S0      
317P12V             J7    -P11  D0300PA00X+027339Y+003252               S0      
317P12V             J7    -P21  D0300PA00X+028339Y+002189               S0      
317P12V             J7    -P12  D0300PA00X+028339Y+003252               S0      
317P12V             VIA   -     D0200PA00X+028810Y+005494               S3      
317P12V             VIA   -     D0200PA00X+028810Y+004557               S3      
317P12V             VIA   -     D0200PA00X+027157Y+005494               S3      
317P12V             VIA   -     D0200PA00X+027975Y+005494               S3      
317P12V             VIA   -     D0200PA00X+027157Y+004557               S3      
317P12V             VIA   -     D0200PA00X+027975Y+004557               S3      
317P12V             VIA   -     D0200PA00X+028810Y+006545               S3      
317P12V             VIA   -     D0200PA00X+027157Y+006545               S3      
317P12V             VIA   -     D0200PA00X+027975Y+006545               S3      
327GND              C14   -2          A01X+028309Y+016626X0180Y0200R090 S2      
327P12V             C14   -1          A01X+028309Y+016941X0180Y0200R090 S2      
327GND              C13   -2          A01X+028742Y+016626X0180Y0200R090 S2      
327P12V             C13   -1          A01X+028742Y+016941X0180Y0200R090 S2      
317GND              VIA   -     D0100PA00X+028742Y+016254               S3      
317GND              VIA   -     D0100PA00X+028309Y+016268               S1      
317P12V             J8    -P22  D0300PA00X+027339Y+019689               S0      
317P12V             J8    -P21  D0300PA00X+028339Y+019689               S0      
317P12V             J8    -P11  D0300PA00X+027339Y+020752               S0      
317P12V             J8    -P12  D0300PA00X+028339Y+020752               S0      
327GND              C9    -2          A01X+027662Y+023844X0180Y0200R270 S2      
327P12V             C9    -1          A01X+027662Y+023529X0180Y0200R270 S2      
327GND              C10   -2          A01X+028119Y+023844X0180Y0200R270 S2      
327P12V             C10   -1          A01X+028119Y+023529X0180Y0200R270 S2      
327P12V             C8    -1          A01X+027155Y+023596X0280Y0320     S2      
327GND              C8    -2          A01X+027155Y+024176X0280Y0320     S2      
317GND              VIA   -     D0100PA00X+027155Y+024535               S1      
317GND              VIA   -     D0100PA00X+027662Y+024140               S3      
317GND              VIA   -     D0100PA00X+028119Y+024162               S1      
327GND              C21   -2          A01X+028107Y+034152X0180Y0200R090 S2      
327P12V             C21   -1          A01X+028107Y+034467X0180Y0200R090 S2      
327GND              C19   -2          A01X+028990Y+034152X0180Y0200R090 S2      
327P12V             C19   -1          A01X+028990Y+034467X0180Y0200R090 S2      
327GND              C20   -2          A01X+028551Y+034152X0180Y0200R090 S2      
327P12V             C20   -1          A01X+028551Y+034467X0180Y0200R090 S2      
317GND              VIA   -     D0100PA00X+028551Y+033769               S3      
317GND              VIA   -     D0100PA00X+028107Y+033769               S1      
317GND              VIA   -     D0100PA00X+028990Y+033769               S1      
317P12V             J9    -P22  D0300PA00X+027339Y+037189               S0      
317P12V             J9    -P21  D0300PA00X+028339Y+037189               S0      
317P12V             J9    -P11  D0300PA00X+027339Y+038252               S0      
317P12V             J9    -P12  D0300PA00X+028339Y+038252               S0      
327GND              C17   -2          A01X+029100Y+041402X0180Y0200R270 S2      
327P12V             C17   -1          A01X+029100Y+041087X0180Y0200R270 S2      
327GND              C16   -2          A01X+028667Y+041402X0180Y0200R270 S2      
327P12V             C16   -1          A01X+028667Y+041087X0180Y0200R270 S2      
327P12V             C15   -1          A01X+028157Y+041154X0280Y0320     S2      
327GND              C15   -2          A01X+028157Y+041734X0280Y0320     S2      
317P12V             VIA   -     D0200PA00X+027453Y+040729               S3      
317P12V             VIA   -     D0200PA00X+027453Y+039677               S3      
317P12V             VIA   -     D0200PA00X+027453Y+041779               S3      
317GND              VIA   -     D0100PA00X+028667Y+041784               S3      
317GND              VIA   -     D0100PA00X+029100Y+041784               S1      
317GND              VIA   -     D0100PA00X+028157Y+042117               S1      
327GND              R116  -2          A01X+027211Y+046310X0180Y0200R180 S2      
327NNAME10034       R116  -1          A01X+026896Y+046310X0180Y0200R180 S2      
317GND              VIA   -     D0100PA00X+027499Y+046310               S3      
327P12V             R115  -2          A01X+027204Y+047368X0180Y0200R180 S2      
327NNAME10045       R115  -1          A01X+026889Y+047368X0180Y0200R180 S2      
317GND              VIA   -     D0100PA00X+028278Y+051234               S3      
317GND              VIA   -     D0100PA00X+027841Y+051234               S1      
317GND              VIA   -     D0100PA00X+027394Y+051234               S3      
317GND              VIA   -     D0100PA00X+026952Y+051234               S1      
327GND              C26   -2          A01X+027841Y+051592X0180Y0200R090 S2      
327P12V             C26   -1          A01X+027841Y+051907X0180Y0200R090 S2      
327GND              C27   -2          A01X+027394Y+051592X0180Y0200R090 S2      
327P12V             C27   -1          A01X+027394Y+051907X0180Y0200R090 S2      
327GND              C25   -2          A01X+028278Y+051592X0180Y0200R090 S2      
327P12V             C25   -1          A01X+028278Y+051907X0180Y0200R090 S2      
327GND              C28   -2          A01X+026952Y+051592X0180Y0200R090 S2      
327P12V             C28   -1          A01X+026952Y+051907X0180Y0200R090 S2      
317P12V             J10   -P22  D0300PA00X+027339Y+054689               S0      
317P12V             J10   -P11  D0300PA00X+027339Y+055752               S0      
317P12V             J10   -P21  D0300PA00X+028339Y+054689               S0      
317P12V             J10   -P12  D0300PA00X+028339Y+055752               S0      
327P12V             C23   -1          A01X+029098Y+058549X0180Y0200R270 S2      
327P12V             C22   -1          A01X+028535Y+058616X0280Y0320     S2      
317P12V             VIA   -     D0200PA00X+027894Y+058144               S3      
317P12V             VIA   -     D0200PA00X+027894Y+057264               S3      
327GND              C23   -2          A01X+029098Y+058864X0180Y0200R270 S2      
327GND              C22   -2          A01X+028535Y+059196X0280Y0320     S2      
317P12V             VIA   -     D0200PA00X+027894Y+060128               S3      
317P12V             VIA   -     D0200PA00X+027894Y+060901               S3      
317P12V             VIA   -     D0200PA00X+027894Y+059195               S3      
317GND              VIA   -     D0100PA00X+028535Y+059554               S1      
317GND              VIA   -     D0100PA00X+029098Y+059222               S3      
317P12V             VIA   -     D0200PA00X+027894Y+061745               S3      
317GND              VIA   -     D0200PA00X+027904Y+062463               S3      
327GND              C32   -2          A01X+028334Y+069112X0180Y0200R090 S2      
327P12V             C32   -1          A01X+028334Y+069427X0180Y0200R090 S2      
327GND              C33   -2          A01X+027896Y+069112X0180Y0200R090 S2      
327P12V             C33   -1          A01X+027896Y+069427X0180Y0200R090 S2      
327GND              C34   -2          A01X+027451Y+069112X0180Y0200R090 S2      
327P12V             C34   -1          A01X+027451Y+069427X0180Y0200R090 S2      
327GND              C35   -2          A01X+027011Y+069112X0180Y0200R090 S2      
327P12V             C35   -1          A01X+027011Y+069427X0180Y0200R090 S2      
317GND              VIA   -     D0100PA00X+027451Y+068719               S3      
317GND              VIA   -     D0100PA00X+027011Y+068719               S1      
317GND              VIA   -     D0100PA00X+028334Y+068719               S3      
317GND              VIA   -     D0100PA00X+027896Y+068719               S1      
317P12V             J11   -P22  D0300PA00X+027339Y+072189               S0      
317P12V             J11   -P11  D0300PA00X+027339Y+073252               S0      
317P12V             J11   -P21  D0300PA00X+028339Y+072189               S0      
317P12V             J11   -P12  D0300PA00X+028339Y+073252               S0      
327GND              C30   -2          A01X+027818Y+076371X0180Y0200R270 S2      
327P12V             C30   -1          A01X+027818Y+076056X0180Y0200R270 S2      
327GND              C31   -2          A01X+028274Y+076371X0180Y0200R270 S2      
327P12V             C31   -1          A01X+028274Y+076056X0180Y0200R270 S2      
327P12V             C29   -1          A01X+027311Y+076124X0280Y0320     S2      
327GND              C29   -2          A01X+027311Y+076704X0280Y0320     S2      
317GND              VIA   -     D0100PA00X+027311Y+077097               S1      
317GND              VIA   -     D0100PA00X+027818Y+076764               S3      
317GND              VIA   -     D0100PA00X+028274Y+076764               S1      
317GND              VIA   -     D0100PA00X+027007Y+081219               S3      
327GND              C39   -2          A01X+028579Y+086624X0180Y0200R090 S2      
327P12V             C39   -1          A01X+028579Y+086939X0180Y0200R090 S2      
327GND              C40   -2          A01X+028131Y+086624X0180Y0200R090 S2      
327P12V             C40   -1          A01X+028131Y+086939X0180Y0200R090 S2      
327GND              C41   -2          A01X+027669Y+086624X0180Y0200R090 S2      
327P12V             C41   -1          A01X+027669Y+086939X0180Y0200R090 S2      
327GND              C42   -2          A01X+027218Y+086624X0180Y0200R090 S2      
327P12V             C42   -1          A01X+027218Y+086939X0180Y0200R090 S2      
317GND              VIA   -     D0100PA00X+027669Y+086249               S3      
317GND              VIA   -     D0100PA00X+027218Y+086235               S1      
317GND              VIA   -     D0100PA00X+028579Y+086224               S3      
317GND              VIA   -     D0100PA00X+028131Y+086224               S1      
317P12V             J12   -P22  D0300PA00X+027339Y+089689               S0      
317P12V             J12   -P21  D0300PA00X+028339Y+089689               S0      
317P12V             J12   -P11  D0300PA00X+027339Y+090752               S0      
317P12V             J12   -P12  D0300PA00X+028339Y+090752               S0      
327GND              C37   -2          A01X+028119Y+093744X0180Y0200R270 S2      
327P12V             C37   -1          A01X+028119Y+093429X0180Y0200R270 S2      
327GND              C38   -2          A01X+028587Y+093744X0180Y0200R270 S2      
327P12V             C38   -1          A01X+028587Y+093429X0180Y0200R270 S2      
327P12V             C36   -1          A01X+027597Y+093496X0280Y0320     S2      
327GND              C36   -2          A01X+027597Y+094076X0280Y0320     S2      
317P12V             VIA   -     D0200PA00X+027454Y+094934               S3      
317GND              VIA   -     D0100PA00X+027597Y+094477               S1      
317GND              VIA   -     D0100PA00X+028119Y+094144               S3      
317GND              VIA   -     D0100PA00X+028587Y+094144               S1      
317P12V             VIA   -     D0200PA00X+027454Y+096711               S3      
317P12V             VIA   -     D0200PA00X+027454Y+095986               S3      
317P12V             VIA   -     D0200PA00X+027440Y+097439               S3      
317P12V             VIA   -     D0200PA00X+027440Y+099055               S3      
317P12V             VIA   -     D0200PA00X+027440Y+098211               S3      
327GND              C47   -2          A01X+029011Y+103488X0180Y0200R090 S2      
327P12V             C47   -1          A01X+029011Y+103803X0180Y0200R090 S2      
327GND              C48   -2          A01X+028567Y+103488X0180Y0200R090 S2      
327P12V             C48   -1          A01X+028567Y+103803X0180Y0200R090 S2      
327GND              C49   -2          A01X+028112Y+103488X0180Y0200R090 S2      
327P12V             C49   -1          A01X+028112Y+103803X0180Y0200R090 S2      
317GND              VIA   -     D0100PA00X+028567Y+103116               S3      
317GND              VIA   -     D0100PA00X+028112Y+103116               S1      
317GND              VIA   -     D0100PA00X+029011Y+103116               S1      
317P12V             J13   -P22  D0300PA00X+027339Y+107189               S0      
317P12V             J13   -P21  D0300PA00X+028339Y+107189               S0      
317P12V             J13   -P11  D0300PA00X+027339Y+108252               S0      
317P12V             J13   -P12  D0300PA00X+028339Y+108252               S0      
327GND              C44   -2          A01X+028819Y+111243X0180Y0200R270 S2      
327P12V             C44   -1          A01X+028819Y+110928X0180Y0200R270 S2      
327P12V             C43   -1          A01X+028296Y+110995X0280Y0320     S2      
327GND              C43   -2          A01X+028296Y+111575X0280Y0320     S2      
317GND              VIA   -     D0100PA00X+028296Y+111947               S1      
317GND              VIA   -     D0100PA00X+028819Y+111615               S3      
317P12V             VIA   -     D0200PA00X+027902Y+112408               S3      
317P12V             VIA   -     D0200PA00X+028836Y+112394               S3      
317P12V             VIA   -     D0200PA00X+027902Y+113459               S3      
317P12V             VIA   -     D0200PA00X+028836Y+113445               S3      
317P12V             VIA   -     D0200PA00X+026998Y+113474               S3      
317P12V             VIA   -     D0200PA00X+026998Y+112422               S3      
317P12V             VIA   -     D0200PA00X+028836Y+114496               S3      
317P12V             VIA   -     D0200PA00X+027902Y+114510               S3      
317P12V             VIA   -     D0200PA00X+026998Y+114524               S3      
317P12V             VIA   -     D0200PA00X+028672Y+118431               S3      
317P12V             VIA   -     D0200PA00X+028672Y+119204               S3      
317P12V             VIA   -     D0200PA00X+027818Y+118446               S3      
317P12V             VIA   -     D0200PA00X+027818Y+119218               S3      
327GND              C55   -2          A01X+028419Y+121031X0180Y0200R090 S2      
327P12V             C55   -1          A01X+028419Y+121346X0180Y0200R090 S2      
327GND              C54   -2          A01X+028908Y+121031X0180Y0200R090 S2      
327P12V             C54   -1          A01X+028908Y+121346X0180Y0200R090 S2      
327GND              C56   -2          A01X+027956Y+121031X0180Y0200R090 S2      
327P12V             C56   -1          A01X+027956Y+121346X0180Y0200R090 S2      
317P12V             VIA   -     D0200PA00X+028672Y+120048               S3      
317P12V             VIA   -     D0200PA00X+027818Y+120062               S3      
317GND              VIA   -     D0100PA00X+028908Y+120678               S1      
317GND              VIA   -     D0100PA00X+028419Y+120678               S3      
317GND              VIA   -     D0100PA00X+027956Y+120678               S1      
317P12V             J14   -P22  D0300PA00X+027339Y+124689               S0      
317P12V             J14   -P11  D0300PA00X+027339Y+125752               S0      
317P12V             J14   -P21  D0300PA00X+028339Y+124689               S0      
317P12V             J14   -P12  D0300PA00X+028339Y+125752               S0      
327GND              C51   -2          A01X+028921Y+128710X0180Y0200R270 S2      
327P12V             C51   -1          A01X+028921Y+128395X0180Y0200R270 S2      
327P12V             C50   -1          A01X+028381Y+128462X0280Y0320     S2      
317P12V             VIA   -     D0200PA00X+027062Y+128295               S3      
317P12V             VIA   -     D0200PA00X+027062Y+127243               S3      
327GND              C50   -2          A01X+028381Y+129042X0280Y0320     S2      
317P12V             VIA   -     D0200PA00X+027062Y+129345               S3      
317P12V             VIA   -     D0200PA00X+027062Y+130279               S3      
317P12V             VIA   -     D0200PA00X+027062Y+131052               S3      
317GND              VIA   -     D0100PA00X+028381Y+129396               S1      
317GND              VIA   -     D0100PA00X+028921Y+129063               S3      
317P12V             VIA   -     D0200PA00X+027062Y+131895               S3      
327GND              C60   -2          A01X+028424Y+139334X0180Y0200R090 S2      
327P12V             C60   -1          A01X+028424Y+139649X0180Y0200R090 S2      
327GND              C61   -2          A01X+027952Y+139334X0180Y0200R090 S2      
327P12V             C61   -1          A01X+027952Y+139649X0180Y0200R090 S2      
327GND              C62   -2          A01X+027505Y+139334X0180Y0200R090 S2      
327P12V             C62   -1          A01X+027505Y+139649X0180Y0200R090 S2      
327GND              C63   -2          A01X+027058Y+139334X0180Y0200R090 S2      
327P12V             C63   -1          A01X+027058Y+139649X0180Y0200R090 S2      
317GND              VIA   -     D0100PA00X+028424Y+138954               S3      
317GND              VIA   -     D0100PA00X+027952Y+138954               S1      
317GND              VIA   -     D0100PA00X+027505Y+138972               S3      
317GND              VIA   -     D0100PA00X+027058Y+138963               S1      
317P12V             J15   -P22  D0300PA00X+027339Y+142189               S0      
317P12V             J15   -P11  D0300PA00X+027339Y+143252               S0      
317P12V             J15   -P21  D0300PA00X+028339Y+142189               S0      
317P12V             J15   -P12  D0300PA00X+028339Y+143252               S0      
327P12V             C58   -1          A01X+027552Y+145749X0180Y0200R270 S2      
327P12V             C59   -1          A01X+027999Y+145749X0180Y0200R270 S2      
327P12V             C57   -1          A01X+027023Y+145816X0280Y0320     S2      
327GND              C58   -2          A01X+027552Y+146064X0180Y0200R270 S2      
327GND              C59   -2          A01X+027999Y+146064X0180Y0200R270 S2      
327GND              C57   -2          A01X+027023Y+146396X0280Y0320     S2      
317GND              VIA   -     D0100PA00X+027023Y+146776               S1      
317GND              VIA   -     D0100PA00X+027552Y+146444               S3      
317GND              VIA   -     D0100PA00X+027999Y+146444               S1      
317P12V             VIA   -     D0200PA00X+027840Y+154819               S3      
317P12V             VIA   -     D0200PA00X+027153Y+154801               S3      
317P12V             VIA   -     D0200PA00X+028600Y+154819               S3      
317P12V             VIA   -     D0200PA00X+027840Y+153432               S3      
317P12V             VIA   -     D0200PA00X+027840Y+154124               S3      
317P12V             VIA   -     D0200PA00X+027153Y+153414               S3      
317P12V             VIA   -     D0200PA00X+027153Y+154106               S3      
317P12V             VIA   -     D0200PA00X+028600Y+153432               S3      
317P12V             VIA   -     D0200PA00X+028600Y+154124               S3      
327GND              C69   -2          A01X+028968Y+156245X0180Y0200R090 S2      
327P12V             C69   -1          A01X+028968Y+156560X0180Y0200R090 S2      
327GND              C70   -2          A01X+028505Y+156245X0180Y0200R090 S2      
327P12V             C70   -1          A01X+028505Y+156560X0180Y0200R090 S2      
317GND              VIA   -     D0100PA00X+028968Y+155821               S3      
317GND              VIA   -     D0100PA00X+028505Y+155821               S1      
317P12V             J16   -P22  D0300PA00X+027339Y+159689               S0      
317P12V             J16   -P21  D0300PA00X+028339Y+159689               S0      
317P12V             J16   -P11  D0300PA00X+027339Y+160752               S0      
317P12V             J16   -P12  D0300PA00X+028339Y+160752               S0      
317P12V             VIA   -     D0200PA00X+027334Y+162182               S3      
327GND              C65   -2          A01X+028942Y+163732X0180Y0200R270 S2      
327P12V             C65   -1          A01X+028942Y+163417X0180Y0200R270 S2      
327P12V             C64   -1          A01X+028409Y+163484X0280Y0320     S2      
327GND              C64   -2          A01X+028409Y+164064X0280Y0320     S2      
317P12V             VIA   -     D0200PA00X+027334Y+164284               S3      
317P12V             VIA   -     D0200PA00X+027334Y+163234               S3      
317GND              VIA   -     D0100PA00X+028409Y+164488               S1      
317GND              VIA   -     D0100PA00X+028942Y+164156               S3      
317P12V             VIA   -     D0200PA00X+027334Y+166835               S3      
317P12V             VIA   -     D0200PA00X+027334Y+165218               S3      
317P12V             VIA   -     D0200PA00X+027334Y+165991               S3      
327GND              C74   -2          A01X+028950Y+174192X0180Y0200R090 S2      
327P12V             C74   -1          A01X+028950Y+174507X0180Y0200R090 S2      
327GND              C75   -2          A01X+028458Y+174192X0180Y0200R090 S2      
327P12V             C75   -1          A01X+028458Y+174507X0180Y0200R090 S2      
327GND              C77   -2          A01X+027470Y+174192X0180Y0200R090 S2      
327P12V             C77   -1          A01X+027470Y+174507X0180Y0200R090 S2      
327GND              C76   -2          A01X+027970Y+174192X0180Y0200R090 S2      
327P12V             C76   -1          A01X+027970Y+174507X0180Y0200R090 S2      
317GND              VIA   -     D0100PA00X+027470Y+173820               S1      
317GND              VIA   -     D0100PA00X+027970Y+173840               S3      
317GND              VIA   -     D0100PA00X+028458Y+173847               S1      
317GND              VIA   -     D0100PA00X+028950Y+173874               S3      
317P12V             J17   -P22  D0300PA00X+027339Y+177189               S0      
317P12V             J17   -P21  D0300PA00X+028339Y+177189               S0      
317P12V             J17   -P11  D0300PA00X+027339Y+178252               S0      
317P12V             J17   -P12  D0300PA00X+028339Y+178252               S0      
327GND              C72   -2          A01X+028662Y+181155X0180Y0200R270 S2      
327P12V             C72   -1          A01X+028662Y+180840X0180Y0200R270 S2      
327GND              C73   -2          A01X+029155Y+181155X0180Y0200R270 S2      
327P12V             C73   -1          A01X+029155Y+180840X0180Y0200R270 S2      
327P12V             C71   -1          A01X+028107Y+180907X0280Y0320     S2      
327GND              C71   -2          A01X+028107Y+181487X0280Y0320     S2      
317GND              VIA   -     D0100PA00X+028107Y+181957               S1      
317GND              VIA   -     D0100PA00X+029155Y+181485               S1      
317GND              VIA   -     D0100PA00X+028662Y+181440               S3      
327P12V             R131  -2          A01X+028871Y+186457X0180Y0200R180 S2      
327NNAME10050       R131  -1          A01X+028556Y+186457X0180Y0200R180 S2      
327GND              R132  -2          A01X+028879Y+185867X0180Y0200R180 S2      
327NNAME10041       R132  -1          A01X+028564Y+185867X0180Y0200R180 S2      
317NNAME10041       VIA   -     D0100PA00X+028024Y+185867               S1      
317NNAME10050       VIA   -     D0100PA00X+027998Y+186457               S1      
317GND              VIA   -     D0100PA00X+028712Y+191333               S3      
317GND              VIA   -     D0100PA00X+028272Y+191333               S1      
317GND              VIA   -     D0100PA00X+027826Y+191333               S3      
317GND              VIA   -     D0100PA00X+027382Y+191333               S1      
327GND              C81   -2          A01X+028712Y+191690X0180Y0200R090 S2      
327P12V             C81   -1          A01X+028712Y+192005X0180Y0200R090 S2      
327GND              C82   -2          A01X+028272Y+191690X0180Y0200R090 S2      
327P12V             C82   -1          A01X+028272Y+192005X0180Y0200R090 S2      
327GND              C83   -2          A01X+027826Y+191690X0180Y0200R090 S2      
327P12V             C83   -1          A01X+027826Y+192005X0180Y0200R090 S2      
327GND              C84   -2          A01X+027382Y+191690X0180Y0200R090 S2      
327P12V             C84   -1          A01X+027382Y+192005X0180Y0200R090 S2      
317P12V             J18   -P22  D0300PA00X+027339Y+194689               S0      
317P12V             J18   -P11  D0300PA00X+027339Y+195752               S0      
317P12V             J18   -P21  D0300PA00X+028339Y+194689               S0      
317P12V             J18   -P12  D0300PA00X+028339Y+195752               S0      
317P12V             VIA   -     D0200PA00X+027012Y+203148               S3      
317P12V             VIA   -     D0200PA00X+027012Y+202097               S3      
317P12V             VIA   -     D0200PA00X+027012Y+205132               S3      
317P12V             VIA   -     D0200PA00X+027012Y+205905               S3      
317P12V             VIA   -     D0200PA00X+027012Y+204199               S3      
317P12V             VIA   -     D0200PA00X+027012Y+206749               S3      
317P12V             J7    -P20  D0300PA00X+029339Y+002189               S0      
317P12V             J7    -P13  D0300PA00X+029339Y+003252               S0      
317P12V             J7    -P19  D0300PA00X+030339Y+002189               S0      
317P12V             J7    -P14  D0300PA00X+030339Y+003252               S0      
317P12V             J7    -P15  D0300PA00X+031339Y+003252               S0      
317P12V             J7    -P18  D0300PA00X+031339Y+002189               S0      
327GND              C3    -2          A01X+030415Y+006039X0180Y0200R270 S2      
327P12V             C3    -1          A01X+030415Y+005724X0180Y0200R270 S2      
327GND              C4    -2          A01X+030865Y+006039X0180Y0200R270 S2      
327P12V             C4    -1          A01X+030865Y+005724X0180Y0200R270 S2      
327GND              C5    -2          A01X+031309Y+006039X0180Y0200R270 S2      
327P12V             C5    -1          A01X+031309Y+005724X0180Y0200R270 S2      
327GND              C2    -2          A01X+029969Y+006039X0180Y0200R270 S2      
327P12V             C2    -1          A01X+029969Y+005724X0180Y0200R270 S2      
327P12V             C1    -1          A01X+029448Y+005792X0280Y0320     S2      
327GND              C1    -2          A01X+029448Y+006372X0280Y0320     S2      
317GND              VIA   -     D0100PA00X+029969Y+006378               S3      
317GND              VIA   -     D0100PA00X+030415Y+006378               S1      
317GND              VIA   -     D0100PA00X+030865Y+006378               S3      
317GND              VIA   -     D0100PA00X+031309Y+006378               S1      
317GND              VIA   -     D0100PA00X+029448Y+006773               S1      
317GND              H12   -6    D0220PA00X+030709Y+011339               S0      
317GND              H12   -5    D0220PA00X+029724Y+011732               S0      
317GND              H12   -4    D0220PA00X+029331Y+012717               S0      
317N/C              H12   -1    D1580UA00X+030709Y+012717               S0      
317GND              H12   -3    D0220PA00X+029724Y+013701               S0      
317GND              H12   -2    D0220PA00X+030709Y+014095               S0      
327GND              C12   -2          A01X+029194Y+016626X0180Y0200R090 S2      
327P12V             C12   -1          A01X+029194Y+016941X0180Y0200R090 S2      
327GND              C11   -2          A01X+029652Y+016626X0180Y0200R090 S2      
327P12V             C11   -1          A01X+029652Y+016941X0180Y0200R090 S2      
317GND              VIA   -     D0100PA00X+029652Y+016259               S3      
317GND              VIA   -     D0100PA00X+029194Y+016263               S1      
317P12V             J8    -P20  D0300PA00X+029339Y+019689               S0      
317P12V             J8    -P19  D0300PA00X+030339Y+019689               S0      
317P12V             J8    -P18  D0300PA00X+031339Y+019689               S0      
317P12V             J8    -P13  D0300PA00X+029339Y+020752               S0      
317P12V             J8    -P14  D0300PA00X+030339Y+020752               S0      
317P12V             J8    -P15  D0300PA00X+031339Y+020752               S0      
317T2_BLAD1_RXD     VIA   -     D0100PA00X+030806Y+024886               S1      
317T2_BLAD1_TXD     VIA   -     D0100PA00X+030627Y+024101               S1      
317T2_BLAD3_TXD     VIA   -     D0100PA00X+031491Y+023816               S1      
317T2_BLAD1_EN      VIA   -     D0100PA00X+031494Y+025208               S1      
317T2_BLAD4_EN      VIA   -     D0100PA00X+030587Y+025859               S1      
317N/C              H14   -1    D2050UA00X+030709Y+030827               S0      
327GND              C18   -2          A01X+029451Y+034152X0180Y0200R090 S2      
327P12V             C18   -1          A01X+029451Y+034467X0180Y0200R090 S2      
317GND              VIA   -     D0100PA00X+029451Y+033769               S3      
317P12V             J9    -P20  D0300PA00X+029339Y+037189               S0      
317P12V             J9    -P19  D0300PA00X+030339Y+037189               S0      
317P12V             J9    -P18  D0300PA00X+031339Y+037189               S0      
317P12V             J9    -P13  D0300PA00X+029339Y+038252               S0      
317P12V             J9    -P14  D0300PA00X+030339Y+038252               S0      
317P12V             J9    -P15  D0300PA00X+031339Y+038252               S0      
317GND              H9    -6    D0220PA00X+030709Y+046339               S0      
317GND              H9    -5    D0220PA00X+029724Y+046732               S0      
317GND              H9    -4    D0220PA00X+029331Y+047717               S0      
317GND              H9    -3    D0220PA00X+029724Y+048701               S0      
317GND              H9    -2    D0220PA00X+030709Y+049095               S0      
317N/C              H9    -1    D1580UA00X+030709Y+047717               S0      
317P12V             VIA   -     D0200PA00X+030054Y+051631               S3      
317P12V             VIA   -     D0200PA00X+030797Y+051642               S3      
317P12V             VIA   -     D0200PA00X+030797Y+052415               S3      
317P12V             VIA   -     D0200PA00X+030054Y+052404               S3      
317P12V             VIA   -     D0200PA00X+030054Y+053248               S3      
317P12V             VIA   -     D0200PA00X+030797Y+053259               S3      
317P12V             VIA   -     D0200PA00X+029257Y+052432               S3      
317P12V             VIA   -     D0200PA00X+029257Y+051660               S3      
317P12V             VIA   -     D0200PA00X+029257Y+053276               S3      
317P12V             J10   -P20  D0300PA00X+029339Y+054689               S0      
317P12V             J10   -P13  D0300PA00X+029339Y+055752               S0      
317P12V             J10   -P19  D0300PA00X+030339Y+054689               S0      
317P12V             J10   -P14  D0300PA00X+030339Y+055752               S0      
317P12V             J10   -P15  D0300PA00X+031339Y+055752               S0      
317P12V             J10   -P18  D0300PA00X+031339Y+054689               S0      
327P12V             C24   -1          A01X+029551Y+058549X0180Y0200R270 S2      
327GND              C24   -2          A01X+029551Y+058864X0180Y0200R270 S2      
317GND              VIA   -     D0100PA00X+029551Y+059222               S1      
317P12V             VIA   -     D0200PA00X+031519Y+065246               S3      
317P12V             VIA   -     D0200PA00X+031519Y+066126               S3      
317P12V             VIA   -     D0200PA00X+030415Y+066126               S3      
317P12V             VIA   -     D0200PA00X+030415Y+065246               S3      
317P12V             VIA   -     D0200PA00X+030415Y+068110               S3      
317P12V             VIA   -     D0200PA00X+031519Y+068110               S3      
317P12V             VIA   -     D0200PA00X+031519Y+067176               S3      
317P12V             VIA   -     D0200PA00X+030415Y+067176               S3      
317P12V             VIA   -     D0200PA00X+031519Y+068883               S3      
317P12V             VIA   -     D0200PA00X+030415Y+068883               S3      
317P12V             VIA   -     D0200PA00X+030415Y+069727               S3      
317P12V             VIA   -     D0200PA00X+031519Y+069727               S3      
317P12V             J11   -P20  D0300PA00X+029339Y+072189               S0      
317P12V             J11   -P13  D0300PA00X+029339Y+073252               S0      
317P12V             J11   -P19  D0300PA00X+030339Y+072189               S0      
317P12V             J11   -P14  D0300PA00X+030339Y+073252               S0      
317P12V             J11   -P15  D0300PA00X+031339Y+073252               S0      
317P12V             J11   -P18  D0300PA00X+031339Y+072189               S0      
317GND              H7    -6    D0220PA00X+030709Y+081339               S0      
317GND              H7    -5    D0220PA00X+029724Y+081732               S0      
317GND              H7    -4    D0220PA00X+029331Y+082717               S0      
317N/C              H7    -1    D1580UA00X+030709Y+082717               S0      
317GND              H7    -3    D0220PA00X+029724Y+083701               S0      
317GND              H7    -2    D0220PA00X+030709Y+084095               S0      
317P12V             J12   -P20  D0300PA00X+029339Y+089689               S0      
317P12V             J12   -P19  D0300PA00X+030339Y+089689               S0      
317P12V             J12   -P18  D0300PA00X+031339Y+089689               S0      
317P12V             J12   -P13  D0300PA00X+029339Y+090752               S0      
317P12V             J12   -P14  D0300PA00X+030339Y+090752               S0      
317P12V             J12   -P15  D0300PA00X+031339Y+090752               S0      
317P12V             VIA   -     D0200PA00X+030719Y+102066               S3      
317P12V             VIA   -     D0200PA00X+030708Y+100730               S3      
317P12V             VIA   -     D0200PA00X+030727Y+100129               S3      
317P12V             VIA   -     D0200PA00X+030714Y+101409               S3      
327GND              C46   -2          A01X+029462Y+103488X0180Y0200R090 S2      
327P12V             C46   -1          A01X+029462Y+103803X0180Y0200R090 S2      
317P12V             VIA   -     D0200PA00X+030713Y+102708               S3      
317P12V             VIA   -     D0200PA00X+030700Y+103372               S3      
317GND              VIA   -     D0100PA00X+029462Y+103116               S3      
317P12V             J13   -P20  D0300PA00X+029339Y+107189               S0      
317P12V             J13   -P19  D0300PA00X+030339Y+107189               S0      
317P12V             J13   -P18  D0300PA00X+031339Y+107189               S0      
317T7_BLAD2_TXD     VIA   -     D0100PA00X+030968Y+105326               S1      
317P12V             J13   -P13  D0300PA00X+029339Y+108252               S0      
317P12V             J13   -P14  D0300PA00X+030339Y+108252               S0      
317P12V             J13   -P15  D0300PA00X+031339Y+108252               S0      
327GND              C45   -2          A01X+029270Y+111243X0180Y0200R270 S2      
327P12V             C45   -1          A01X+029270Y+110928X0180Y0200R270 S2      
317GND              VIA   -     D0100PA00X+029270Y+111615               S1      
317NNAME10038       VIA   -     D0100PA00X+031253Y+116227               S1      
317P12V             VIA   -     D0200PA00X+030316Y+118453               S3      
317P12V             VIA   -     D0200PA00X+030316Y+119225               S3      
317P12V             VIA   -     D0200PA00X+031194Y+119225               S3      
317P12V             VIA   -     D0200PA00X+031194Y+118453               S3      
317P12V             VIA   -     D0200PA00X+029469Y+118453               S3      
317P12V             VIA   -     D0200PA00X+029469Y+119225               S3      
317NNAME10047       VIA   -     D0100PA00X+031270Y+117280               S1      
327GND              C53   -2          A01X+029381Y+121031X0180Y0200R090 S2      
327P12V             C53   -1          A01X+029381Y+121346X0180Y0200R090 S2      
317P12V             VIA   -     D0200PA00X+031194Y+120069               S3      
317P12V             VIA   -     D0200PA00X+030316Y+120069               S3      
317P12V             VIA   -     D0200PA00X+029469Y+120069               S3      
317GND              VIA   -     D0100PA00X+029381Y+120678               S3      
317P12V             J14   -P20  D0300PA00X+029339Y+124689               S0      
317P12V             J14   -P13  D0300PA00X+029339Y+125752               S0      
317P12V             J14   -P19  D0300PA00X+030339Y+124689               S0      
317P12V             J14   -P14  D0300PA00X+030339Y+125752               S0      
317P12V             J14   -P15  D0300PA00X+031339Y+125752               S0      
317P12V             J14   -P18  D0300PA00X+031339Y+124689               S0      
327GND              C52   -2          A01X+029413Y+128710X0180Y0200R270 S2      
327P12V             C52   -1          A01X+029413Y+128395X0180Y0200R270 S2      
317GND              VIA   -     D0100PA00X+029413Y+129063               S1      
317GND              H5    -6    D0220PA00X+030709Y+132972               S0      
317GND              H5    -5    D0220PA00X+029724Y+133366               S0      
317N/C              H5    -1    D1580UA00X+030709Y+134350               S0      
317GND              H5    -4    D0220PA00X+029331Y+134350               S0      
317GND              H5    -3    D0220PA00X+029724Y+135335               S0      
317GND              H5    -2    D0220PA00X+030709Y+135728               S0      
317T9_BLAD3_EN      VIA   -     D0100PA00X+031418Y+140342               S1      
317P12V             J15   -P20  D0300PA00X+029339Y+142189               S0      
317P12V             J15   -P13  D0300PA00X+029339Y+143252               S0      
317P12V             J15   -P19  D0300PA00X+030339Y+142189               S0      
317P12V             J15   -P14  D0300PA00X+030339Y+143252               S0      
317P12V             J15   -P15  D0300PA00X+031339Y+143252               S0      
317P12V             J15   -P18  D0300PA00X+031339Y+142189               S0      
317P12V             VIA   -     D0200PA00X+030982Y+147296               S3      
317P12V             VIA   -     D0200PA00X+030946Y+148010               S3      
317P12V             VIA   -     D0200PA00X+030982Y+146600               S3      
317P12V             VIA   -     D0200PA00X+030982Y+145909               S3      
317P12V             VIA   -     D0200PA00X+029272Y+148010               S3      
317P12V             VIA   -     D0200PA00X+029290Y+147295               S3      
317P12V             VIA   -     D0200PA00X+030107Y+147295               S3      
317P12V             VIA   -     D0200PA00X+030089Y+148010               S3      
317P12V             VIA   -     D0200PA00X+029290Y+145908               S3      
317P12V             VIA   -     D0200PA00X+029290Y+146600               S3      
317P12V             VIA   -     D0200PA00X+030107Y+146600               S3      
317P12V             VIA   -     D0200PA00X+030107Y+145908               S3      
317P12V             VIA   -     D0200PA00X+030946Y+149397               S3      
317P12V             VIA   -     D0200PA00X+030946Y+148702               S3      
317P12V             VIA   -     D0200PA00X+029272Y+148702               S3      
317P12V             VIA   -     D0200PA00X+029272Y+149397               S3      
317P12V             VIA   -     D0200PA00X+030089Y+149397               S3      
317P12V             VIA   -     D0200PA00X+030089Y+148702               S3      
327P12V             R127  -2          A01X+030891Y+152440X0180Y0200R180 S2      
327NNAME10048       R127  -1          A01X+030576Y+152440X0180Y0200R180 S2      
327GND              R128  -2          A01X+030864Y+151388X0180Y0200R180 S2      
327NNAME10040       R128  -1          A01X+030549Y+151388X0180Y0200R180 S2      
317GND              VIA   -     D0100PA00X+031389Y+151388               S3      
317NNAME10048       VIA   -     D0100PA00X+030227Y+152440               S1      
317NNAME10040       VIA   -     D0100PA00X+030173Y+151388               S1      
327GND              C67   -2          A01X+029887Y+156245X0180Y0200R090 S2      
327P12V             C67   -1          A01X+029887Y+156560X0180Y0200R090 S2      
327GND              C68   -2          A01X+029439Y+156245X0180Y0200R090 S2      
327P12V             C68   -1          A01X+029439Y+156560X0180Y0200R090 S2      
317T10_BLAD1_EN     VIA   -     D0100PA00X+031208Y+157587               S1      
317GND              VIA   -     D0100PA00X+029887Y+155821               S3      
317GND              VIA   -     D0100PA00X+029439Y+155821               S1      
317P12V             J16   -P20  D0300PA00X+029339Y+159689               S0      
317P12V             J16   -P19  D0300PA00X+030339Y+159689               S0      
317P12V             J16   -P18  D0300PA00X+031339Y+159689               S0      
317P12V             J16   -P13  D0300PA00X+029339Y+160752               S0      
317P12V             J16   -P14  D0300PA00X+030339Y+160752               S0      
317P12V             J16   -P15  D0300PA00X+031339Y+160752               S0      
327GND              C66   -2          A01X+029409Y+163732X0180Y0200R270 S2      
327P12V             C66   -1          A01X+029409Y+163417X0180Y0200R270 S2      
317GND              VIA   -     D0100PA00X+029409Y+164156               S1      
317GND              H3    -6    D0220PA00X+030709Y+167972               S0      
317GND              H3    -5    D0220PA00X+029724Y+168366               S0      
317GND              H3    -4    D0220PA00X+029331Y+169350               S0      
317N/C              H3    -1    D1580UA00X+030709Y+169350               S0      
317GND              H3    -3    D0220PA00X+029724Y+170335               S0      
317GND              H3    -2    D0220PA00X+030709Y+170728               S0      
317P12V             J17   -P20  D0300PA00X+029339Y+177189               S0      
317P12V             J17   -P19  D0300PA00X+030339Y+177189               S0      
317P12V             J17   -P18  D0300PA00X+031339Y+177189               S0      
317T11_BLAD1_EN     VIA   -     D0100PA00X+031154Y+175350               S1      
317P12V             J17   -P13  D0300PA00X+029339Y+178252               S0      
317P12V             J17   -P14  D0300PA00X+030339Y+178252               S0      
317P12V             J17   -P15  D0300PA00X+031339Y+178252               S0      
317P12V             VIA   -     D0100PA00X+029261Y+186457               S3      
317GND              VIA   -     D0100PA00X+029361Y+185867               S3      
317N/C              H13   -1    D2050UA00X+030709Y+188307               S0      
317P12V             VIA   -     D0200PA00X+029275Y+191715               S3      
317P12V             VIA   -     D0200PA00X+030035Y+191715               S3      
317P12V             VIA   -     D0200PA00X+029275Y+191023               S3      
317P12V             VIA   -     D0200PA00X+030035Y+191023               S3      
317P12V             VIA   -     D0200PA00X+030722Y+191041               S3      
317P12V             VIA   -     D0200PA00X+031481Y+191041               S3      
317P12V             VIA   -     D0200PA00X+031481Y+191733               S3      
317P12V             VIA   -     D0200PA00X+030722Y+191733               S3      
317P12V             VIA   -     D0200PA00X+029275Y+192410               S3      
317P12V             VIA   -     D0200PA00X+030035Y+192410               S3      
317P12V             VIA   -     D0200PA00X+031481Y+192428               S3      
317P12V             VIA   -     D0200PA00X+030722Y+192428               S3      
317P12V             J18   -P20  D0300PA00X+029339Y+194689               S0      
317P12V             J18   -P13  D0300PA00X+029339Y+195752               S0      
317P12V             J18   -P19  D0300PA00X+030339Y+194689               S0      
317P12V             J18   -P14  D0300PA00X+030339Y+195752               S0      
317P12V             J18   -P15  D0300PA00X+031339Y+195752               S0      
317P12V             J18   -P18  D0300PA00X+031339Y+194689               S0      
327P12V             C78   -1          A01X+031456Y+198361X0280Y0320     S2      
327GND              C78   -2          A01X+031456Y+198941X0280Y0320     S2      
317GND              VIA   -     D0100PA00X+031456Y+199409               S1      
317GND              H1    -6    D0220PA00X+030709Y+202972               S0      
317GND              H1    -5    D0220PA00X+029724Y+203366               S0      
317N/C              H1    -1    D1580UA00X+030709Y+204350               S0      
317GND              H1    -4    D0220PA00X+029331Y+204350               S0      
317GND              H1    -3    D0220PA00X+029724Y+205335               S0      
317GND              H1    -2    D0220PA00X+030709Y+205728               S0      
317GND              VIA   -     D0100PA00X+030999Y+208361               S3      
317GND              VIA   -     D0100PA00X+032522Y+000300               S3      
317T1_BLAD3_TXD     J7    -S12  D0300PA00X+033717Y+002471               S0      
317P12V             J7    -P16  D0300PA00X+032339Y+003252               S0      
317P12V             J7    -P17  D0300PA00X+032339Y+002189               S0      
317T1_BLAD1_TXD     J7    -S1   D0300PA00X+033717Y+003471               S0      
317T1_BLAD4_RXD     VIA   -     D0100PA00X+033140Y+005141               S1      
317T1_BLAD4_TXD     VIA   -     D0100PA00X+033389Y+005602               S1      
327GND              C6    -2          A01X+031757Y+006039X0180Y0200R270 S2      
327P12V             C6    -1          A01X+031757Y+005724X0180Y0200R270 S2      
327GND              C7    -2          A01X+032201Y+006039X0180Y0200R270 S2      
327P12V             C7    -1          A01X+032201Y+005724X0180Y0200R270 S2      
317T1_BLAD3_RXD     VIA   -     D0100PA00X+033823Y+006156               S1      
317GND              VIA   -     D0100PA00X+032201Y+006378               S1      
317GND              VIA   -     D0100PA00X+031757Y+006378               S3      
317GND              H12   -8    D0220PA00X+032087Y+012717               S0      
317GND              H12   -7    D0220PA00X+031693Y+011732               S0      
317GND              H12   -9    D0220PA00X+031693Y+013701               S0      
317T2_BLAD3_TXD     J8    -S12  D0300PA00X+033717Y+019971               S0      
317P12V             J8    -P17  D0300PA00X+032339Y+019689               S0      
317T2_BLAD1_TXD     J8    -S1   D0300PA00X+033717Y+020971               S0      
317P12V             J8    -P16  D0300PA00X+032339Y+020752               S0      
317T2_BLAD4_TXD     VIA   -     D0100PA00X+032037Y+022598               S1      
317T2_BLAD4_RXD     VIA   -     D0100PA00X+031809Y+023182               S1      
317T2_BLAD2_RXD     VIA   -     D0100PA00X+032190Y+023814               S1      
317T2_BLAD2_EN      VIA   -     D0100PA00X+032993Y+024568               S1      
317T2_BLAD2_TXD     VIA   -     D0100PA00X+033105Y+023202               S1      
317T2_BLAD3_EN      VIA   -     D0100PA00X+032096Y+025011               S1      
317T2_BLAD3_RXD     VIA   -     D0100PA00X+032471Y+023158               S1      
317P12V             VIA   -     D0200PA00X+033278Y+031863               S3      
317P12V             VIA   -     D0200PA00X+033269Y+031198               S3      
317P12V             VIA   -     D0200PA00X+033278Y+033527               S3      
317P12V             VIA   -     D0200PA00X+033278Y+034246               S3      
317P12V             VIA   -     D0200PA00X+033278Y+032594               S3      
317P12V             J9    -P17  D0300PA00X+032339Y+037189               S0      
317P12V             VIA   -     D0200PA00X+033269Y+034866               S3      
317T3_BLAD3_TXD     J9    -S12  D0300PA00X+033717Y+037471               S0      
317T3_BLAD1_TXD     J9    -S1   D0300PA00X+033717Y+038471               S0      
317P12V             J9    -P16  D0300PA00X+032339Y+038252               S0      
317T3_BLAD2_TXD     VIA   -     D0100PA00X+033552Y+040403               S1      
317T3_BLAD4_RXD     VIA   -     D0100PA00X+032331Y+041831               S1      
317T3_BLAD3_TXD     VIA   -     D0100PA00X+032620Y+041398               S1      
317T3_BLAD3_RXD     VIA   -     D0100PA00X+032895Y+040922               S1      
317T3_BLAD4_TXD     VIA   -     D0100PA00X+032098Y+042323               S1      
317GND              H9    -7    D0220PA00X+031693Y+046732               S0      
317GND              H9    -9    D0220PA00X+031693Y+048701               S0      
317GND              H9    -8    D0220PA00X+032087Y+047717               S0      
317P12V             VIA   -     D0200PA00X+032514Y+051663               S3      
317P12V             VIA   -     D0200PA00X+032514Y+052436               S3      
317P12V             VIA   -     D0200PA00X+031679Y+052443               S3      
317P12V             VIA   -     D0200PA00X+031679Y+051670               S3      
317P12V             VIA   -     D0200PA00X+031679Y+053287               S3      
317P12V             VIA   -     D0200PA00X+032514Y+053280               S3      
317T4_BLAD3_TXD     J10   -S12  D0300PA00X+033717Y+054971               S0      
317T4_BLAD1_TXD     J10   -S1   D0300PA00X+033717Y+055971               S0      
317P12V             J10   -P16  D0300PA00X+032339Y+055752               S0      
317P12V             J10   -P17  D0300PA00X+032339Y+054689               S0      
317T4_BLAD3_RXD     VIA   -     D0100PA00X+033662Y+057798               S1      
317T4_BLAD3_EN      VIA   -     D0100PA00X+031931Y+058211               S1      
317T4_BLAD4_TXD     VIA   -     D0100PA00X+032964Y+058472               S1      
317T4_BLAD1_RXD     VIA   -     D0100PA00X+031772Y+058825               S1      
317T4_BLAD2_TXD     VIA   -     D0100PA00X+033739Y+058623               S1      
317T4_BLAD1_TXD     VIA   -     D0100PA00X+032038Y+057649               S1      
317T4_BLAD4_RXD     VIA   -     D0100PA00X+033187Y+058981               S1      
317T4_BLAD3_TXD     VIA   -     D0100PA00X+033375Y+059533               S1      
317T4_BLAD2_EN      VIA   -     D0100PA00X+032375Y+058916               S1      
317T4_BLAD4_EN      VIA   -     D0100PA00X+031985Y+059333               S1      
317T4_BLAD1_EN      VIA   -     D0100PA00X+032174Y+059904               S1      
317T5_BLAD3_TXD     J11   -S12  D0300PA00X+033717Y+072471               S0      
317P12V             J11   -P16  D0300PA00X+032339Y+073252               S0      
317P12V             J11   -P17  D0300PA00X+032339Y+072189               S0      
317T5_BLAD1_TXD     J11   -S1   D0300PA00X+033717Y+073471               S0      
317T5_BLAD3_RXD     VIA   -     D0100PA00X+033157Y+075297               S1      
317T5_BLAD2_TXD     VIA   -     D0100PA00X+033901Y+075286               S1      
317T5_BLAD4_TXD     VIA   -     D0100PA00X+032934Y+076269               S1      
317T5_BLAD3_TXD     VIA   -     D0100PA00X+033401Y+075859               S1      
317T5_BLAD4_RXD     VIA   -     D0100PA00X+032752Y+075802               S1      
317GND              H7    -8    D0220PA00X+032087Y+082717               S0      
317GND              H7    -7    D0220PA00X+031693Y+081732               S0      
317GND              H7    -9    D0220PA00X+031693Y+083701               S0      
317T6_BLAD3_TXD     J12   -S12  D0300PA00X+033717Y+089971               S0      
317P12V             J12   -P17  D0300PA00X+032339Y+089689               S0      
317T6_BLAD1_TXD     J12   -S1   D0300PA00X+033717Y+090971               S0      
317P12V             J12   -P16  D0300PA00X+032339Y+090752               S0      
317T6_BLAD2_EN      VIA   -     D0100PA00X+033962Y+092636               S1      
317T6_BLAD3_TXD     VIA   -     D0100PA00X+032994Y+094876               S1      
317T6_BLAD3_RXD     VIA   -     D0100PA00X+033253Y+094375               S1      
317T6_BLAD1_RXD     VIA   -     D0100PA00X+032410Y+094610               S1      
317T6_BLAD4_TXD     VIA   -     D0100PA00X+031856Y+094118               S1      
317T6_BLAD4_RXD     VIA   -     D0100PA00X+032387Y+092998               S1      
317T6_BLAD3_EN      VIA   -     D0100PA00X+032665Y+093979               S1      
317T6_BLAD4_EN      VIA   -     D0100PA00X+033330Y+092846               S1      
317T6_BLAD2_TXD     VIA   -     D0100PA00X+033616Y+093726               S1      
317T6_BLAD1_EN      VIA   -     D0100PA00X+032858Y+093326               S1      
317T6_BLAD1_TXD     VIA   -     D0100PA00X+032143Y+095158               S1      
317P12V             VIA   -     D0200PA00X+031824Y+102066               S3      
317P12V             VIA   -     D0200PA00X+031832Y+100129               S3      
317P12V             VIA   -     D0200PA00X+031812Y+100730               S3      
317P12V             VIA   -     D0200PA00X+031818Y+101409               S3      
317P12V             VIA   -     D0200PA00X+031817Y+102708               S3      
317P12V             VIA   -     D0200PA00X+031804Y+103372               S3      
317P12V             J13   -P17  D0300PA00X+032339Y+107189               S0      
317T7_BLAD3_RXD     VIA   -     D0100PA00X+032425Y+105179               S1      
317T7_BLAD4_RXD     VIA   -     D0100PA00X+033568Y+104890               S1      
317T7_BLAD3_TXD     VIA   -     D0100PA00X+031759Y+105305               S1      
317T7_BLAD3_TXD     J13   -S12  D0300PA00X+033717Y+107471               S0      
317T7_BLAD1_TXD     J13   -S1   D0300PA00X+033717Y+108471               S0      
317P12V             J13   -P16  D0300PA00X+032339Y+108252               S0      
317T7_BLAD4_EN      VIA   -     D0100PA00X+033192Y+111609               S1      
317T7_BLAD1_EN      VIA   -     D0100PA00X+033751Y+110960               S1      
317T7_BLAD1_RXD     VIA   -     D0100PA00X+032899Y+112109               S1      
317T7_BLAD1_TXD     VIA   -     D0100PA00X+032656Y+112637               S1      
327GND              R124  -2          A01X+032021Y+116227X0180Y0200R180 S2      
327NNAME10038       R124  -1          A01X+031706Y+116227X0180Y0200R180 S2      
317GND              VIA   -     D0100PA00X+032580Y+116227               S3      
327P12V             R123  -2          A01X+032026Y+117280X0180Y0200R180 S2      
327NNAME10047       R123  -1          A01X+031711Y+117280X0180Y0200R180 S2      
317P12V             VIA   -     D0100PA00X+032340Y+117280               S3      
317T8_BLAD3_TXD     J14   -S12  D0300PA00X+033717Y+124971               S0      
317T8_BLAD1_TXD     J14   -S1   D0300PA00X+033717Y+125971               S0      
317P12V             J14   -P16  D0300PA00X+032339Y+125752               S0      
317P12V             J14   -P17  D0300PA00X+032339Y+124689               S0      
317T8_BLAD1_RXD     VIA   -     D0100PA00X+032745Y+127945               S1      
317T8_BLAD1_TXD     VIA   -     D0100PA00X+032198Y+128209               S1      
317T8_BLAD2_EN      VIA   -     D0100PA00X+033805Y+128260               S1      
317T8_BLAD4_EN      VIA   -     D0100PA00X+033324Y+127681               S1      
317T8_BLAD1_EN      VIA   -     D0100PA00X+032962Y+128402               S1      
317T8_BLAD3_EN      VIA   -     D0100PA00X+032793Y+128922               S1      
317GND              H5    -7    D0220PA00X+031693Y+133366               S0      
317GND              H5    -9    D0220PA00X+031693Y+135335               S0      
317GND              H5    -8    D0220PA00X+032087Y+134350               S0      
317T9_BLAD4_EN      VIA   -     D0100PA00X+031940Y+140135               S1      
317T9_BLAD1_RXD     VIA   -     D0100PA00X+032564Y+139911               S1      
317T9_BLAD4_TXD     VIA   -     D0100PA00X+033465Y+140080               S1      
317T9_BLAD3_TXD     J15   -S12  D0300PA00X+033717Y+142471               S0      
317T9_BLAD1_TXD     J15   -S1   D0300PA00X+033717Y+143471               S0      
317P12V             J15   -P16  D0300PA00X+032339Y+143252               S0      
317P12V             J15   -P17  D0300PA00X+032339Y+142189               S0      
317T10_BLAD3_EN     VIA   -     D0100PA00X+032372Y+157092               S1      
317T10_BLAD4_EN     VIA   -     D0100PA00X+032940Y+157194               S1      
317T10_BLAD2_EN     VIA   -     D0100PA00X+031724Y+157483               S1      
317T10_BLAD1_TXD    VIA   -     D0100PA00X+033347Y+156669               S1      
317T10_BLAD1_RXD    VIA   -     D0100PA00X+033596Y+157380               S1      
317T10_BLAD3_TXD    J16   -S12  D0300PA00X+033717Y+159971               S0      
317P12V             J16   -P17  D0300PA00X+032339Y+159689               S0      
317T10_BLAD1_TXD    J16   -S1   D0300PA00X+033717Y+160971               S0      
317P12V             J16   -P16  D0300PA00X+032339Y+160752               S0      
317GND              H3    -8    D0220PA00X+032087Y+169350               S0      
317GND              H3    -7    D0220PA00X+031693Y+168366               S0      
317GND              H3    -9    D0220PA00X+031693Y+170335               S0      
317P12V             J17   -P17  D0300PA00X+032339Y+177189               S0      
317T11_BLAD3_EN     VIA   -     D0100PA00X+032989Y+175208               S1      
317T11_BLAD2_EN     VIA   -     D0100PA00X+032128Y+175347               S1      
317T11_BLAD4_EN     VIA   -     D0100PA00X+033573Y+175327               S1      
317T11_BLAD3_TXD    J17   -S12  D0300PA00X+033717Y+177471               S0      
317T11_BLAD1_TXD    J17   -S1   D0300PA00X+033717Y+178471               S0      
317P12V             J17   -P16  D0300PA00X+032339Y+178252               S0      
317T12_BLAD2_EN     VIA   -     D0100PA00X+033831Y+192762               S1      
317T12_BLAD1_EN     VIA   -     D0100PA00X+033240Y+192679               S1      
317T12_BLAD3_TXD    J18   -S12  D0300PA00X+033717Y+194971               S0      
317T12_BLAD1_TXD    J18   -S1   D0300PA00X+033717Y+195971               S0      
317P12V             J18   -P16  D0300PA00X+032339Y+195752               S0      
317P12V             J18   -P17  D0300PA00X+032339Y+194689               S0      
327GND              C79   -2          A01X+032005Y+198703X0180Y0200R270 S2      
327P12V             C79   -1          A01X+032005Y+198388X0180Y0200R270 S2      
327GND              C80   -2          A01X+032480Y+198703X0180Y0200R270 S2      
327P12V             C80   -1          A01X+032480Y+198388X0180Y0200R270 S2      
317GND              VIA   -     D0100PA00X+032480Y+199027               S1      
317GND              VIA   -     D0100PA00X+032005Y+199022               S3      
317GND              H1    -7    D0220PA00X+031693Y+203366               S0      
317GND              H1    -9    D0220PA00X+031693Y+205335               S0      
317GND              H1    -8    D0220PA00X+032087Y+204350               S0      
317T1_BLAD3_RXD     J7    -S11  D0300PA00X+034217Y+001971               S0      
317T1_BLAD1_RXD     J7    -S2   D0300PA00X+034217Y+002971               S0      
317T1_BLAD3_EN      J7    -S10  D0300PA00X+034717Y+002471               S0      
317T1_BLAD4_EN      J7    -S9   D0300PA00X+035217Y+001971               S0      
317T1_BLAD2_EN      J7    -S4   D0300PA00X+035217Y+002971               S0      
317T1_BLAD4_TXD     J7    -S8   D0300PA00X+035717Y+002471               S0      
317T1_BLAD4_RXD     J7    -S7   D0300PA00X+036217Y+001971               S0      
317T1_BLAD2_RXD     J7    -S6   D0300PA00X+036217Y+002971               S0      
317T1_BLAD1_EN      J7    -S3   D0300PA00X+034717Y+003471               S0      
317T1_BLAD2_TXD     J7    -S5   D0300PA00X+035717Y+003471               S0      
317T1_BLAD1_TXD     VIA   -     D0100PA00X+035993Y+005219               S1      
317T1_BLAD2_TXD     VIA   -     D0100PA00X+034829Y+005086               S1      
317T1_BLAD2_RXD     VIA   -     D0100PA00X+034509Y+005619               S1      
317T1_BLAD3_TXD     VIA   -     D0100PA00X+034037Y+005158               S1      
317N/C              H25   -1    D3150UA00X+035984Y+007878               S0      
317T2_BLAD3_RXD     J8    -S11  D0300PA00X+034217Y+019471               S0      
317T2_BLAD3_EN      J8    -S10  D0300PA00X+034717Y+019971               S0      
317T2_BLAD4_EN      J8    -S9   D0300PA00X+035217Y+019471               S0      
317T2_BLAD4_TXD     J8    -S8   D0300PA00X+035717Y+019971               S0      
317T2_BLAD4_RXD     J8    -S7   D0300PA00X+036217Y+019471               S0      
317T2_BLAD1_RXD     J8    -S2   D0300PA00X+034217Y+020471               S0      
317T2_BLAD1_EN      J8    -S3   D0300PA00X+034717Y+020971               S0      
317T2_BLAD2_EN      J8    -S4   D0300PA00X+035217Y+020471               S0      
317T2_BLAD2_TXD     J8    -S5   D0300PA00X+035717Y+020971               S0      
317T2_BLAD2_RXD     J8    -S6   D0300PA00X+036217Y+020471               S0      
317N/C              H16   -1    D3150UA00X+035984Y+025378               S0      
317P12V             VIA   -     D0200PA00X+034382Y+031863               S3      
317P12V             VIA   -     D0200PA00X+034373Y+031198               S3      
317P12V             VIA   -     D0200PA00X+034382Y+033527               S3      
317P12V             VIA   -     D0200PA00X+034382Y+034246               S3      
317P12V             VIA   -     D0200PA00X+034382Y+032594               S3      
317T3_BLAD3_RXD     J9    -S11  D0300PA00X+034217Y+036971               S0      
317T3_BLAD4_EN      J9    -S9   D0300PA00X+035217Y+036971               S0      
317T3_BLAD4_RXD     J9    -S7   D0300PA00X+036217Y+036971               S0      
317P12V             VIA   -     D0200PA00X+034373Y+034866               S3      
317T3_BLAD1_RXD     J9    -S2   D0300PA00X+034217Y+037971               S0      
317T3_BLAD3_EN      J9    -S10  D0300PA00X+034717Y+037471               S0      
317T3_BLAD1_EN      J9    -S3   D0300PA00X+034717Y+038471               S0      
317T3_BLAD2_EN      J9    -S4   D0300PA00X+035217Y+037971               S0      
317T3_BLAD4_TXD     J9    -S8   D0300PA00X+035717Y+037471               S0      
317T3_BLAD2_TXD     J9    -S5   D0300PA00X+035717Y+038471               S0      
317T3_BLAD2_RXD     J9    -S6   D0300PA00X+036217Y+037971               S0      
317N/C              H17   -1    D3150UA00X+035984Y+042878               S0      
317T3_BLAD2_RXD     VIA   -     D0100PA00X+034210Y+040168               S1      
317T3_BLAD1_TXD     VIA   -     D0100PA00X+036383Y+040177               S1      
317T4_BLAD3_RXD     J10   -S11  D0300PA00X+034217Y+054471               S0      
317T4_BLAD1_RXD     J10   -S2   D0300PA00X+034217Y+055471               S0      
317T4_BLAD3_EN      J10   -S10  D0300PA00X+034717Y+054971               S0      
317T4_BLAD1_EN      J10   -S3   D0300PA00X+034717Y+055971               S0      
317T4_BLAD4_EN      J10   -S9   D0300PA00X+035217Y+054471               S0      
317T4_BLAD2_EN      J10   -S4   D0300PA00X+035217Y+055471               S0      
317T4_BLAD4_TXD     J10   -S8   D0300PA00X+035717Y+054971               S0      
317T4_BLAD2_TXD     J10   -S5   D0300PA00X+035717Y+055971               S0      
317T4_BLAD4_RXD     J10   -S7   D0300PA00X+036217Y+054471               S0      
317T4_BLAD2_RXD     J10   -S6   D0300PA00X+036217Y+055471               S0      
317N/C              H22   -1    D3150UA00X+035984Y+060378               S0      
317T4_BLAD2_RXD     VIA   -     D0100PA00X+034290Y+058013               S1      
317T5_BLAD3_RXD     J11   -S11  D0300PA00X+034217Y+071971               S0      
317T5_BLAD1_RXD     J11   -S2   D0300PA00X+034217Y+072971               S0      
317T5_BLAD3_EN      J11   -S10  D0300PA00X+034717Y+072471               S0      
317T5_BLAD4_EN      J11   -S9   D0300PA00X+035217Y+071971               S0      
317T5_BLAD2_EN      J11   -S4   D0300PA00X+035217Y+072971               S0      
317T5_BLAD4_TXD     J11   -S8   D0300PA00X+035717Y+072471               S0      
317T5_BLAD4_RXD     J11   -S7   D0300PA00X+036217Y+071971               S0      
317T5_BLAD2_RXD     J11   -S6   D0300PA00X+036217Y+072971               S0      
317T5_BLAD1_EN      J11   -S3   D0300PA00X+034717Y+073471               S0      
317T5_BLAD2_TXD     J11   -S5   D0300PA00X+035717Y+073471               S0      
317T5_BLAD1_TXD     VIA   -     D0100PA00X+036258Y+075278               S1      
317T5_BLAD2_RXD     VIA   -     D0100PA00X+034411Y+075181               S1      
317N/C              H20   -1    D3150UA00X+035984Y+077878               S0      
317T6_BLAD3_RXD     J12   -S11  D0300PA00X+034217Y+089471               S0      
317T6_BLAD3_EN      J12   -S10  D0300PA00X+034717Y+089971               S0      
317T6_BLAD4_EN      J12   -S9   D0300PA00X+035217Y+089471               S0      
317T6_BLAD4_TXD     J12   -S8   D0300PA00X+035717Y+089971               S0      
317T6_BLAD4_RXD     J12   -S7   D0300PA00X+036217Y+089471               S0      
317T6_BLAD1_RXD     J12   -S2   D0300PA00X+034217Y+090471               S0      
317T6_BLAD1_EN      J12   -S3   D0300PA00X+034717Y+090971               S0      
317T6_BLAD2_EN      J12   -S4   D0300PA00X+035217Y+090471               S0      
317T6_BLAD2_TXD     J12   -S5   D0300PA00X+035717Y+090971               S0      
317T6_BLAD2_RXD     J12   -S6   D0300PA00X+036217Y+090471               S0      
317N/C              H18   -1    D3150UA00X+035984Y+095378               S0      
317T6_BLAD2_RXD     VIA   -     D0100PA00X+034366Y+093373               S1      
317T7_BLAD3_RXD     J13   -S11  D0300PA00X+034217Y+106971               S0      
317T7_BLAD4_EN      J13   -S9   D0300PA00X+035217Y+106971               S0      
317T7_BLAD4_RXD     J13   -S7   D0300PA00X+036217Y+106971               S0      
317T7_BLAD4_TXD     VIA   -     D0100PA00X+034558Y+104784               S1      
317T7_BLAD1_RXD     J13   -S2   D0300PA00X+034217Y+107971               S0      
317T7_BLAD3_EN      J13   -S10  D0300PA00X+034717Y+107471               S0      
317T7_BLAD1_EN      J13   -S3   D0300PA00X+034717Y+108471               S0      
317T7_BLAD2_EN      J13   -S4   D0300PA00X+035217Y+107971               S0      
317T7_BLAD4_TXD     J13   -S8   D0300PA00X+035717Y+107471               S0      
317T7_BLAD2_TXD     J13   -S5   D0300PA00X+035717Y+108471               S0      
317T7_BLAD2_RXD     J13   -S6   D0300PA00X+036217Y+107971               S0      
317N/C              H21   -1    D3150UA00X+035984Y+112878               S0      
317T7_BLAD3_EN      VIA   -     D0100PA00X+034410Y+110680               S1      
317T7_BLAD2_EN      VIA   -     D0100PA00X+034986Y+110430               S1      
317T8_BLAD3_RXD     J14   -S11  D0300PA00X+034217Y+124471               S0      
317T8_BLAD1_RXD     J14   -S2   D0300PA00X+034217Y+125471               S0      
317T8_BLAD3_EN      J14   -S10  D0300PA00X+034717Y+124971               S0      
317T8_BLAD1_EN      J14   -S3   D0300PA00X+034717Y+125971               S0      
317T8_BLAD4_EN      J14   -S9   D0300PA00X+035217Y+124471               S0      
317T8_BLAD2_EN      J14   -S4   D0300PA00X+035217Y+125471               S0      
317T8_BLAD4_TXD     J14   -S8   D0300PA00X+035717Y+124971               S0      
317T8_BLAD2_TXD     J14   -S5   D0300PA00X+035717Y+125971               S0      
317T8_BLAD4_RXD     J14   -S7   D0300PA00X+036217Y+124471               S0      
317T8_BLAD2_RXD     J14   -S6   D0300PA00X+036217Y+125471               S0      
317N/C              H26   -1    D3150UA00X+035984Y+130378               S0      
317GND              VIA   -     D0200PA00X+035439Y+132969               S3      
317GND              VIA   -     D0200PA00X+035439Y+135071               S3      
317GND              VIA   -     D0200PA00X+035439Y+136004               S3      
317GND              VIA   -     D0200PA00X+035439Y+134020               S3      
317GND              VIA   -     D0200PA00X+035439Y+137621               S3      
317GND              VIA   -     D0200PA00X+035439Y+136777               S3      
317T9_BLAD4_RXD     VIA   -     D0100PA00X+034413Y+140167               S1      
317T9_BLAD1_TXD     VIA   -     D0100PA00X+035069Y+140324               S1      
317T9_BLAD3_RXD     J15   -S11  D0300PA00X+034217Y+141971               S0      
317T9_BLAD1_RXD     J15   -S2   D0300PA00X+034217Y+142971               S0      
317T9_BLAD3_EN      J15   -S10  D0300PA00X+034717Y+142471               S0      
317T9_BLAD1_EN      J15   -S3   D0300PA00X+034717Y+143471               S0      
317T9_BLAD4_EN      J15   -S9   D0300PA00X+035217Y+141971               S0      
317T9_BLAD2_EN      J15   -S4   D0300PA00X+035217Y+142971               S0      
317T9_BLAD4_TXD     J15   -S8   D0300PA00X+035717Y+142471               S0      
317T9_BLAD2_TXD     J15   -S5   D0300PA00X+035717Y+143471               S0      
317T9_BLAD4_RXD     J15   -S7   D0300PA00X+036217Y+141971               S0      
317T9_BLAD2_RXD     J15   -S6   D0300PA00X+036217Y+142971               S0      
317N/C              H23   -1    D3150UA00X+035984Y+147878               S0      
317T10_BLAD2_TXD    VIA   -     D0100PA00X+034871Y+157019               S1      
317T10_BLAD4_TXD    VIA   -     D0100PA00X+036101Y+156889               S1      
317T10_BLAD2_RXD    VIA   -     D0100PA00X+034340Y+157208               S1      
317T10_BLAD3_TXD    VIA   -     D0100PA00X+034825Y+157524               S1      
317T10_BLAD3_RXD    VIA   -     D0100PA00X+035536Y+157099               S1      
317T10_BLAD3_RXD    J16   -S11  D0300PA00X+034217Y+159471               S0      
317T10_BLAD3_EN     J16   -S10  D0300PA00X+034717Y+159971               S0      
317T10_BLAD4_EN     J16   -S9   D0300PA00X+035217Y+159471               S0      
317T10_BLAD4_TXD    J16   -S8   D0300PA00X+035717Y+159971               S0      
317T10_BLAD4_RXD    J16   -S7   D0300PA00X+036217Y+159471               S0      
317T10_BLAD1_RXD    J16   -S2   D0300PA00X+034217Y+160471               S0      
317T10_BLAD1_EN     J16   -S3   D0300PA00X+034717Y+160971               S0      
317T10_BLAD2_EN     J16   -S4   D0300PA00X+035217Y+160471               S0      
317T10_BLAD2_TXD    J16   -S5   D0300PA00X+035717Y+160971               S0      
317T10_BLAD2_RXD    J16   -S6   D0300PA00X+036217Y+160471               S0      
317N/C              H15   -1    D3150UA00X+035984Y+165378               S0      
317T11_BLAD3_RXD    J17   -S11  D0300PA00X+034217Y+176971               S0      
317T11_BLAD4_EN     J17   -S9   D0300PA00X+035217Y+176971               S0      
317T11_BLAD4_RXD    J17   -S7   D0300PA00X+036217Y+176971               S0      
317T11_BLAD1_RXD    J17   -S2   D0300PA00X+034217Y+177971               S0      
317T11_BLAD3_EN     J17   -S10  D0300PA00X+034717Y+177471               S0      
317T11_BLAD1_EN     J17   -S3   D0300PA00X+034717Y+178471               S0      
317T11_BLAD2_EN     J17   -S4   D0300PA00X+035217Y+177971               S0      
317T11_BLAD4_TXD    J17   -S8   D0300PA00X+035717Y+177471               S0      
317T11_BLAD2_TXD    J17   -S5   D0300PA00X+035717Y+178471               S0      
317T11_BLAD2_RXD    J17   -S6   D0300PA00X+036217Y+177971               S0      
317N/C              H19   -1    D3150UA00X+035984Y+182878               S0      
317T12_BLAD1_RXD    VIA   -     D0100PA00X+034554Y+191656               S1      
317T12_BLAD1_TXD    VIA   -     D0100PA00X+034440Y+191112               S1      
317T12_BLAD2_TXD    VIA   -     D0100PA00X+036336Y+191831               S1      
317T12_BLAD2_RXD    VIA   -     D0100PA00X+035832Y+192068               S1      
317T12_BLAD3_RXD    VIA   -     D0100PA00X+036341Y+192346               S1      
317T12_BLAD3_EN     VIA   -     D0100PA00X+034034Y+192241               S1      
317T12_BLAD4_EN     VIA   -     D0100PA00X+034768Y+192217               S1      
317T12_BLAD3_RXD    J18   -S11  D0300PA00X+034217Y+194471               S0      
317T12_BLAD1_RXD    J18   -S2   D0300PA00X+034217Y+195471               S0      
317T12_BLAD3_EN     J18   -S10  D0300PA00X+034717Y+194971               S0      
317T12_BLAD1_EN     J18   -S3   D0300PA00X+034717Y+195971               S0      
317T12_BLAD4_EN     J18   -S9   D0300PA00X+035217Y+194471               S0      
317T12_BLAD2_EN     J18   -S4   D0300PA00X+035217Y+195471               S0      
317T12_BLAD4_TXD    J18   -S8   D0300PA00X+035717Y+194971               S0      
317T12_BLAD2_TXD    J18   -S5   D0300PA00X+035717Y+195971               S0      
317T12_BLAD4_RXD    J18   -S7   D0300PA00X+036217Y+194471               S0      
317T12_BLAD2_RXD    J18   -S6   D0300PA00X+036217Y+195471               S0      
317N/C              H24   -1    D3150UA00X+035984Y+200378               S0      
327N/C                    -1          A08X+034483Y+203527X0390Y0390     S1      
317GND              VIA   -     D0100PA00X+035999Y+208361               S3      
317GND              VIA   -     D0100PA00X+037522Y+000300               S3      
317N/C              J7    -H1   D0990UA00X+037339Y+003252               S0      
317T1_BLAD1_EN      VIA   -     D0100PA00X+037220Y+005613               S1      
317T1_BLAD4_EN      VIA   -     D0100PA00X+036572Y+005234               S1      
317T1_BLAD3_EN      VIA   -     D0100PA00X+037926Y+005216               S1      
327N/C                    -1          A01X+038859Y+006211X0390Y0390     S2      
327N/C                    -1          A08X+038957Y+006618X0390Y0390     S1      
317T1_BLAD2_EN      VIA   -     D0100PA00X+037957Y+005844               S1      
317T1_BLAD1_RXD     VIA   -     D0100PA00X+038752Y+007685               S1      
317N/C              J8    -H1   D0990UA00X+037339Y+020752               S0      
317N/C              J9    -H1   D0990UA00X+037339Y+038252               S0      
317T3_BLAD1_RXD     VIA   -     D0100PA00X+037444Y+040686               S1      
317T3_BLAD4_EN      VIA   -     D0100PA00X+038062Y+041011               S1      
317T3_BLAD2_EN      VIA   -     D0100PA00X+038088Y+040400               S1      
317T3_BLAD1_EN      VIA   -     D0100PA00X+037454Y+040128               S1      
317T3_BLAD3_EN      VIA   -     D0100PA00X+036891Y+040431               S1      
317N/C              J10   -H1   D0990UA00X+037339Y+055752               S0      
317N/C              J11   -H1   D0990UA00X+037339Y+073252               S0      
317T5_BLAD1_EN      VIA   -     D0100PA00X+037665Y+075475               S1      
317T5_BLAD1_RXD     VIA   -     D0100PA00X+038289Y+076771               S1      
317T5_BLAD3_EN      VIA   -     D0100PA00X+038679Y+077434               S1      
317T5_BLAD4_EN      VIA   -     D0100PA00X+038019Y+076174               S1      
317N/C              J12   -H1   D0990UA00X+037339Y+090752               S0      
317N/C              J13   -H1   D0990UA00X+037339Y+108252               S0      
317T8_BLAD3_TXD     VIA   -     D0100PA00X+037934Y+118978               S1      
317T8_BLAD4_RXD     VIA   -     D0100PA00X+038328Y+118414               S1      
317T8_BLAD4_TXD     VIA   -     D0100PA00X+038682Y+117984               S1      
317T8_BLAD3_RXD     VIA   -     D0100PA00X+037647Y+119500               S1      
317T8_BLAD2_RXD     VIA   -     D0100PA00X+037367Y+119997               S1      
317T8_BLAD2_TXD     VIA   -     D0100PA00X+037152Y+120473               S1      
317N/C              J14   -H1   D0990UA00X+037339Y+125752               S0      
317GND              VIA   -     D0200PA00X+036617Y+132969               S3      
317GND              VIA   -     D0200PA00X+036617Y+135071               S3      
317GND              VIA   -     D0200PA00X+036617Y+136004               S3      
317GND              VIA   -     D0200PA00X+036617Y+134020               S3      
317GND              VIA   -     D0200PA00X+036617Y+137621               S3      
317GND              VIA   -     D0200PA00X+036617Y+136777               S3      
317N/C              J15   -H1   D0990UA00X+037339Y+143252               S0      
317T10_BLAD4_RXD    VIA   -     D0100PA00X+036783Y+156611               S1      
317N/C              J16   -H1   D0990UA00X+037339Y+160752               S0      
317N/C              J17   -H1   D0990UA00X+037339Y+178252               S0      
317T12_BLAD4_TXD    VIA   -     D0100PA00X+037478Y+191924               S1      
317T12_BLAD4_RXD    VIA   -     D0100PA00X+037940Y+191726               S1      
317T12_BLAD3_TXD    VIA   -     D0100PA00X+036975Y+192180               S1      
317N/C              J18   -H1   D0990UA00X+037339Y+195752               S0      
327N/C                    -1          A01X+038562Y+199157X0390Y0390     S2      
317GND              VIA   -     D0100PA00X+040251Y+001711               S3      
317GND              VIA   -     D0100PA00X+040251Y+006711               S3      
317GND              VIA   -     D0100PA00X+040251Y+011711               S3      
317GND              VIA   -     D0100PA00X+040251Y+016711               S3      
317GND              VIA   -     D0100PA00X+040251Y+021711               S3      
317GND              VIA   -     D0100PA00X+040251Y+026711               S3      
317GND              VIA   -     D0100PA00X+040251Y+031711               S3      
317GND              VIA   -     D0100PA00X+040251Y+036711               S3      
317GND              VIA   -     D0100PA00X+040251Y+041711               S3      
317GND              VIA   -     D0100PA00X+040251Y+046711               S3      
317GND              VIA   -     D0100PA00X+040251Y+051711               S3      
317GND              VIA   -     D0100PA00X+040251Y+056711               S3      
317GND              VIA   -     D0100PA00X+040251Y+061711               S3      
317GND              VIA   -     D0100PA00X+040251Y+066711               S3      
317GND              VIA   -     D0100PA00X+040251Y+071711               S3      
317GND              VIA   -     D0100PA00X+040251Y+076711               S3      
317T5_BLAD2_EN      VIA   -     D0100PA00X+039128Y+076589               S1      
317GND              VIA   -     D0100PA00X+040251Y+081711               S3      
317GND              VIA   -     D0100PA00X+040251Y+086711               S3      
317GND              VIA   -     D0100PA00X+040251Y+091711               S3      
317GND              VIA   -     D0100PA00X+040251Y+096711               S3      
317GND              VIA   -     D0100PA00X+040251Y+101711               S3      
317GND              VIA   -     D0100PA00X+040251Y+106711               S3      
317GND              VIA   -     D0100PA00X+040251Y+111711               S3      
317GND              VIA   -     D0100PA00X+040251Y+116711               S3      
317GND              VIA   -     D0100PA00X+040251Y+121711               S3      
317GND              VIA   -     D0100PA00X+040251Y+126711               S3      
317GND              VIA   -     D0100PA00X+040251Y+131711               S3      
317GND              VIA   -     D0100PA00X+040251Y+136711               S3      
317GND              VIA   -     D0100PA00X+040251Y+141711               S3      
317GND              VIA   -     D0100PA00X+040251Y+146711               S3      
317GND              VIA   -     D0100PA00X+040251Y+151711               S3      
317GND              VIA   -     D0100PA00X+040251Y+156711               S3      
317GND              VIA   -     D0100PA00X+040251Y+161711               S3      
317GND              VIA   -     D0100PA00X+040251Y+166711               S3      
317GND              VIA   -     D0100PA00X+040251Y+171711               S3      
317GND              VIA   -     D0100PA00X+040251Y+176711               S3      
317GND              VIA   -     D0100PA00X+040251Y+181711               S3      
317GND              VIA   -     D0100PA00X+040251Y+186711               S3      
317GND              VIA   -     D0100PA00X+040251Y+191711               S3      
317GND              VIA   -     D0100PA00X+040251Y+196711               S3      
317GND              VIA   -     D0100PA00X+040251Y+201711               S3      
317GND              VIA   -     D0100PA00X+040251Y+206711               S3      
P  NNAME10000 UART_CTS_P1_L_N
P  NNAME10001 UART_DTR_P1_L_N
P  NNAME10002 UART_DSR_P2_L_N
P  NNAME10003 UART_RTS_P2_L_N
P  NNAME10004 UART_CTS_P5_L_N
P  NNAME10005 UART_DTR_P5_L_N
P  NNAME10006 UART_RTS_P6_L_N
P  NNAME10007 UART_DSR_P6_L_N
P  NNAME10008 POWER_SW3_PWR_CTR_12V
P  NNAME10009 UART_CTS_P2_L_N
P  NNAME10010 UART_DSR_P1_L_N
P  NNAME10011 UART_CTS_P6_L_N
P  NNAME10012 UART_RTS_P1_L_N
P  NNAME10013 UART_DSR_P5_L_N
P  NNAME10014 UART_RTS_P5_L_N
P  NNAME10015 UART_RI_RP5_L_N
P  NNAME10016 UART_DTR_RP5_L_N
P  NNAME10017 UART_RTS_RP5_L_N
P  NNAME10018 UART_CTS_RP6_L_N
P  NNAME10019 UART_CTS_RP5_L_N
P  NNAME10020 POWER_SW1_PWR_CTR_12V
P  NNAME10021 POWER_SW2_PWR_CTR_12V
P  NNAME10022 UART_RTS_RP6_L_N
P  NNAME10023 UART_DTR_P2_L_N
P  NNAME10024 UART_DTR_P6_L_N
P  NNAME10025 UART_RI_RP6_L_N
P  NNAME10026 UART_DTR_RP6_L_N
P  NNAME10027 PSU6_REMOTE_R_P
P  NNAME10028 PSU6_REMOTE_R_N
P  NNAME10029 PSU4_REMOTE_R_P
P  NNAME10030 PSU4_REMOTE_R_N
P  NNAME10031 PSU1_REMOTE_R2_N
P  NNAME10032 PSU1_REMOTE_R_N
P  NNAME10033 PSU2_REMOTE_R_N
P  NNAME10034 PSU2_REMOTE_R2_N
P  NNAME10035 PSU3_REMOTE_R_N
P  NNAME10036 PSU3_REMOTE_R2_N
P  NNAME10037 PSU3_REMOTE_R_P
P  NNAME10038 PSU4_REMOTE_R2_N
P  NNAME10039 PSU5_REMOTE_R_N
P  NNAME10040 PSU5_REMOTE_R2_N
P  NNAME10041 PSU6_REMOTE_R2_N
P  NNAME10042 PSU1_REMOTE_R_P
P  NNAME10043 PSU1_REMOTE_R2_P
P  NNAME10044 PSU2_REMOTE_R_P
P  NNAME10045 PSU2_REMOTE_R2_P
P  NNAME10046 PSU3_REMOTE_R2_P
P  NNAME10047 PSU4_REMOTE_R2_P
P  NNAME10048 PSU5_REMOTE_R2_P
P  NNAME10049 PSU5_REMOTE_R_P
P  NNAME10050 PSU6_REMOTE_R2_P
999
